FILE_TYPE = MACRO_DRAWING;
SET COLOR_WIRE YELLOW;
SET COLOR_PROP MONO;
SET COLOR_DOT WHITE;
SET COLOR_ARC YELLOW;
SET COLOR_BODY GREEN;
SET COLOR_NOTE MONO;
SET PROP_DISPLAY VALUE;
SET PAGE_NUMBER P241;
FORCEADD OFFPAGE..2
(3025 4625);
FORCEPROP 2 LAST $XR0 240 
J 0
(3214 4625);
DISPLAY 0.638298 (3214 4625);
PAINT MONO (3214 4625);
FORCEPROP 1 LAST COMMENT_BODY TRUE
J 0
(2980 4530);
DISPLAY 1.170213 (2980 4530);
PAINT GREEN (2980 4530);
DISPLAY INVISIBLE (2980 4530);
FORCEPROP 2 LAST CDS_LIB mstr_standard
J 0
(3025 4625);
PAINT MONO (3025 4625);
DISPLAY INVISIBLE (3025 4625);
FORCEPROP 1 LAST OFFPAGE TRUE
J 0
(3350 4500);
DISPLAY 1.170213 (3350 4500);
PAINT GREEN (3350 4500);
DISPLAY INVISIBLE (3350 4500);
FORCEPROP 2 LAST PATH I1
J 0
(3375 4665);
DISPLAY 1.021277 (3375 4665);
PAINT ORANGE (3375 4665);
DISPLAY INVISIBLE (3375 4665);
FORCEADD RES..2
(1225 4850);
FORCEPROP 1 LASTPIN (1225 4750) $PN 2
J 0
(1230 4760);
DISPLAY 0.617021 (1230 4760);
PAINT WHITE (1230 4760);
FORCEPROP 1 LAST PART_NUMBER G21796-026
R 1
J 0
(1190 4650);
DISPLAY 0.617021 (1190 4650);
PAINT BLUE (1190 4650);
FORCEPROP 1 LASTPIN (1225 4950) $PN 1
J 0
(1230 4912);
DISPLAY 0.617021 (1230 4912);
PAINT WHITE (1230 4912);
FORCEPROP 1 LAST WATTAGE 1/16W
J 0
(1265 4775);
DISPLAY 0.617021 (1265 4775);
PAINT SKYBLUE (1265 4775);
FORCEPROP 1 LAST MATERIAL CHIP
J 0
(1265 4725);
DISPLAY 0.617021 (1265 4725);
PAINT SKYBLUE (1265 4725);
FORCEPROP 1 LAST PACK_TYPE 0402
J 0
(1265 4675);
DISPLAY 0.617021 (1265 4675);
PAINT SKYBLUE (1265 4675);
FORCEPROP 1 LAST TOLERANCE 1%
J 0
(1270 4825);
DISPLAY 0.617021 (1270 4825);
PAINT SKYBLUE (1270 4825);
FORCEPROP 1 LAST VALUE 1.00K
J 0
(1270 4875);
DISPLAY 0.617021 (1270 4875);
PAINT SKYBLUE (1270 4875);
FORCEPROP 1 LAST LOCATION R7E12
J 0
(1270 4925);
DISPLAY 0.617021 (1270 4925);
PAINT AQUA (1270 4925);
FORCEPROP 2 LAST CDS_LIB mstr_discrete
J 0
(1225 4850);
DISPLAY 1.340426 (1225 4850);
PAINT ORANGE (1225 4850);
DISPLAY INVISIBLE (1225 4850);
FORCEPROP 2 LAST CDS_LOCATION R7E12
J 0
(1270 4925);
DISPLAY 0.617021 (1270 4925);
PAINT AQUA (1270 4925);
DISPLAY INVISIBLE (1270 4925);
FORCEPROP 2 LAST ROOM P5V_STBY_VR
J 0
(1275 4975);
DISPLAY 1.021277 (1275 4975);
PAINT ORANGE (1275 4975);
DISPLAY INVISIBLE (1275 4975);
FORCEPROP 1 LAST PATH I11
J 0
(1275 5025);
DISPLAY 0.978723 (1275 5025);
PAINT WHITE (1275 5025);
DISPLAY INVISIBLE (1275 5025);
FORCEPROP 2 LAST SEC 1
J 0
(1275 5075);
DISPLAY 0.914894 (1275 5075);
PAINT MONO (1275 5075);
DISPLAY INVISIBLE (1275 5075);
FORCEPROP 2 LAST BOM_COST P5V_STBY_VR
J 0
(1275 5025);
DISPLAY 1.021277 (1275 5025);
PAINT ORANGE (1275 5025);
DISPLAY INVISIBLE (1275 5025);
FORCEPROP 2 LAST REUSE_ID 21
J 0
(1275 5075);
DISPLAY 1.361702 (1275 5075);
PAINT ORANGE (1275 5075);
DISPLAY INVISIBLE (1275 5075);
FORCEPROP 2 LAST SEC_TYPE 0402
J 0
(1275 5075);
DISPLAY 1.361702 (1275 5075);
PAINT ORANGE (1275 5075);
DISPLAY INVISIBLE (1275 5075);
FORCEADD CAP..2
(1025 3675);
FORCEPROP 1 LAST VALUE 0.1UF
J 2
(1000 3625);
DISPLAY 0.617021 (1000 3625);
PAINT SKYBLUE (1000 3625);
FORCEPROP 1 LAST TOLERANCE 10%
J 2
(900 3600);
DISPLAY 0.617021 (900 3600);
PAINT SKYBLUE (900 3600);
FORCEPROP 1 LASTPIN (925 3675) $PN 1
J 0
(915 3690);
DISPLAY 0.617021 (915 3690);
PAINT WHITE (915 3690);
FORCEPROP 1 LAST PART_NUMBER 602433-020
J 1
(1025 3575);
DISPLAY 0.617021 (1025 3575);
PAINT BLUE (1025 3575);
FORCEPROP 1 LAST LOCATION C8E6
J 1
(1025 3725);
DISPLAY 0.617021 (1025 3725);
PAINT AQUA (1025 3725);
FORCEPROP 1 LAST MATERIAL X7R
J 0
(1125 3600);
DISPLAY 0.617021 (1125 3600);
PAINT SKYBLUE (1125 3600);
FORCEPROP 1 LASTPIN (1125 3675) $PN 2
J 0
(1085 3690);
DISPLAY 0.617021 (1085 3690);
PAINT WHITE (1085 3690);
FORCEPROP 1 LAST VOLTAGE 25V
J 0
(1075 3625);
DISPLAY 0.617021 (1075 3625);
PAINT SKYBLUE (1075 3625);
FORCEPROP 1 LAST PACK_TYPE 0603LF
J 1
(1200 3700);
DISPLAY 0.617021 (1200 3700);
PAINT SKYBLUE (1200 3700);
FORCEPROP 2 LAST ROOM P5V_STBY_VR
J 0
(1025 3775);
DISPLAY 1.021277 (1025 3775);
PAINT ORANGE (1025 3775);
DISPLAY INVISIBLE (1025 3775);
FORCEPROP 2 LAST CDS_LOCATION C8E6
J 1
(1025 3725);
DISPLAY 0.617021 (1025 3725);
PAINT AQUA (1025 3725);
DISPLAY INVISIBLE (1025 3725);
FORCEPROP 2 LAST CDS_LIB mstr_discrete
J 2
(1025 3675);
DISPLAY 1.340426 (1025 3675);
PAINT ORANGE (1025 3675);
DISPLAY INVISIBLE (1025 3675);
FORCEPROP 2 LAST BOM_COST P5V_STBY_VR
J 0
(1025 3825);
DISPLAY 1.021277 (1025 3825);
PAINT ORANGE (1025 3825);
DISPLAY INVISIBLE (1025 3825);
FORCEPROP 2 LAST REUSE_ID 27
J 2
(1025 3925);
DISPLAY 1.361702 (1025 3925);
PAINT ORANGE (1025 3925);
DISPLAY INVISIBLE (1025 3925);
FORCEPROP 1 LAST PATH I12
J 0
(1025 3875);
DISPLAY 0.978723 (1025 3875);
PAINT WHITE (1025 3875);
DISPLAY INVISIBLE (1025 3875);
FORCEPROP 0 LAST SPOF TRUE
J 0
(1025 3875);
DISPLAY 1.361702 (1025 3875);
PAINT ORANGE (1025 3875);
DISPLAY INVISIBLE (1025 3875);
FORCEPROP 2 LAST SEC 1
J 2
(1025 3925);
DISPLAY 0.914894 (1025 3925);
PAINT MONO (1025 3925);
DISPLAY INVISIBLE (1025 3925);
FORCEPROP 2 LAST SEC_TYPE 0603LF
J 2
(1025 3925);
DISPLAY 1.361702 (1025 3925);
PAINT ORANGE (1025 3925);
DISPLAY INVISIBLE (1025 3925);
FORCEADD CAP..1
(1500 4400);
FORCEPROP 1 LAST PART_NUMBER A36096-046
R 1
J 0
(1450 4200);
DISPLAY 0.617021 (1450 4200);
PAINT BLUE (1450 4200);
FORCEPROP 1 LASTPIN (1500 4500) $PN 1
J 0
(1510 4480);
DISPLAY 0.617021 (1510 4480);
PAINT WHITE (1510 4480);
FORCEPROP 1 LASTPIN (1500 4300) $PN 2
J 0
(1510 4280);
DISPLAY 0.617021 (1510 4280);
PAINT WHITE (1510 4280);
FORCEPROP 1 LAST LOCATION C7E10
J 0
(1550 4450);
DISPLAY 0.617021 (1550 4450);
PAINT AQUA (1550 4450);
FORCEPROP 1 LAST VALUE 1000PF
J 0
(1550 4400);
DISPLAY 0.617021 (1550 4400);
PAINT SKYBLUE (1550 4400);
FORCEPROP 1 LAST TOLERANCE 10%
J 0
(1550 4300);
DISPLAY 0.617021 (1550 4300);
PAINT SKYBLUE (1550 4300);
FORCEPROP 1 LAST PACK_TYPE 0402LF
J 0
(1550 4200);
DISPLAY 0.617021 (1550 4200);
PAINT SKYBLUE (1550 4200);
FORCEPROP 1 LAST VOLTAGE 50V
J 0
(1550 4350);
DISPLAY 0.617021 (1550 4350);
PAINT SKYBLUE (1550 4350);
FORCEPROP 1 LAST MATERIAL X7R
J 0
(1550 4250);
DISPLAY 0.617021 (1550 4250);
PAINT SKYBLUE (1550 4250);
FORCEPROP 2 LAST CDS_LIB mstr_discrete
J 0
(1500 4400);
DISPLAY 1.340426 (1500 4400);
PAINT ORANGE (1500 4400);
DISPLAY INVISIBLE (1500 4400);
FORCEPROP 2 LAST BOM_COST P5V_STBY_VR
J 0
(1550 4550);
DISPLAY 1.021277 (1550 4550);
PAINT ORANGE (1550 4550);
DISPLAY INVISIBLE (1550 4550);
FORCEPROP 2 LAST CDS_LOCATION C7E10
J 0
(1550 4450);
DISPLAY 0.617021 (1550 4450);
PAINT AQUA (1550 4450);
DISPLAY INVISIBLE (1550 4450);
FORCEPROP 1 LAST PATH I14
J 0
(1550 4550);
DISPLAY 0.978723 (1550 4550);
PAINT WHITE (1550 4550);
DISPLAY INVISIBLE (1550 4550);
FORCEPROP 2 LAST ROOM P5V_STBY_VR
J 0
(1550 4500);
DISPLAY 1.021277 (1550 4500);
PAINT ORANGE (1550 4500);
DISPLAY INVISIBLE (1550 4500);
FORCEPROP 2 LAST SEC_TYPE 0402LF
J 0
(1550 4600);
DISPLAY 1.361702 (1550 4600);
PAINT ORANGE (1550 4600);
DISPLAY INVISIBLE (1550 4600);
FORCEPROP 2 LAST REUSE_ID 17
J 0
(1550 4600);
DISPLAY 1.361702 (1550 4600);
PAINT ORANGE (1550 4600);
DISPLAY INVISIBLE (1550 4600);
FORCEPROP 2 LAST SEC 1
J 0
(1550 4600);
DISPLAY 0.914894 (1550 4600);
PAINT MONO (1550 4600);
DISPLAY INVISIBLE (1550 4600);
FORCEADD GND..1
(1500 4150);
FORCEPROP 3 LASTPIN (1500 4200) SIG_NAME GND\g
J 0
(1510 4210);
DISPLAY 0.659574 (1510 4210);
PAINT MONO (1510 4210);
DISPLAY INVISIBLE (1510 4210);
FORCEPROP 1 LAST HDL_POWER GND
J 0
(1500 4300);
DISPLAY 1.191489 (1500 4300);
PAINT GREEN (1500 4300);
DISPLAY INVISIBLE (1500 4300);
FORCEPROP 1 LAST BODY_TYPE PLUMBING
J 0
(1455 4107);
DISPLAY 0.340426 (1455 4107);
PAINT GREEN (1455 4107);
DISPLAY INVISIBLE (1455 4107);
FORCEPROP 2 LAST CDS_LIB mstr_symbols
J 0
(1500 4150);
DISPLAY 1.340426 (1500 4150);
PAINT MONO (1500 4150);
DISPLAY INVISIBLE (1500 4150);
FORCEPROP 1 LAST VOLTAGE 0
J 0
(1500 4150);
DISPLAY 1.340426 (1500 4150);
PAINT SKYBLUE (1500 4150);
DISPLAY INVISIBLE (1500 4150);
FORCEPROP 1 LAST SIZE 1B
J 0
(1575 4100);
DISPLAY 1.191489 (1575 4100);
PAINT GREEN (1575 4100);
DISPLAY INVISIBLE (1575 4100);
FORCEPROP 1 LAST PATH I16
J 0
(1575 4150);
DISPLAY 0.872340 (1575 4150);
PAINT AQUA (1575 4150);
DISPLAY INVISIBLE (1575 4150);
FORCEADD RES..2
(-825 2600);
FORCEPROP 1 LASTPIN (-825 2500) $PN 2
J 0
(-820 2510);
DISPLAY 0.617021 (-820 2510);
PAINT ORANGE (-820 2510);
FORCEPROP 1 LAST MATERIAL CHIP
J 0
(-785 2525);
DISPLAY 0.617021 (-785 2525);
PAINT SKYBLUE (-785 2525);
FORCEPROP 1 LAST PACK_TYPE 0402
J 0
(-785 2425);
DISPLAY 0.617021 (-785 2425);
PAINT SKYBLUE (-785 2425);
FORCEPROP 1 LASTPIN (-825 2700) $PN 1
J 0
(-820 2662);
DISPLAY 0.617021 (-820 2662);
PAINT ORANGE (-820 2662);
FORCEPROP 1 LAST WATTAGE 1/16W
J 0
(-785 2575);
DISPLAY 0.617021 (-785 2575);
PAINT SKYBLUE (-785 2575);
FORCEPROP 1 LAST TOLERANCE 1%
J 0
(-780 2625);
DISPLAY 0.617021 (-780 2625);
PAINT SKYBLUE (-780 2625);
FORCEPROP 1 LAST VALUE 75K
J 0
(-780 2675);
DISPLAY 0.617021 (-780 2675);
PAINT SKYBLUE (-780 2675);
FORCEPROP 1 LAST LOCATION R7E14
J 0
(-780 2725);
DISPLAY 0.617021 (-780 2725);
PAINT AQUA (-780 2725);
FORCEPROP 1 LAST PART_NUMBER G21796-224
J 0
(-785 2475);
DISPLAY 0.617021 (-785 2475);
PAINT BLUE (-785 2475);
FORCEPROP 2 LAST CDS_LIB mstr_discrete
J 0
(-825 2600);
DISPLAY 1.340426 (-825 2600);
PAINT ORANGE (-825 2600);
DISPLAY INVISIBLE (-825 2600);
FORCEPROP 2 LAST CDS_LOCATION R7E14
J 0
(-780 2725);
DISPLAY 0.617021 (-780 2725);
PAINT AQUA (-780 2725);
DISPLAY INVISIBLE (-780 2725);
FORCEPROP 1 LAST PATH I18
J 0
(-775 2775);
DISPLAY 0.978723 (-775 2775);
PAINT WHITE (-775 2775);
DISPLAY INVISIBLE (-775 2775);
FORCEPROP 2 LAST REUSE_ID 8
J 0
(-875 2800);
DISPLAY 1.361702 (-875 2800);
PAINT ORANGE (-875 2800);
DISPLAY INVISIBLE (-875 2800);
FORCEPROP 2 LAST ROOM P5V_STBY_VR
J 0
(-775 2775);
DISPLAY 1.021277 (-775 2775);
PAINT ORANGE (-775 2775);
DISPLAY INVISIBLE (-775 2775);
FORCEPROP 2 LAST BOM_COST P5V_STBY_VR
J 0
(-775 2825);
DISPLAY 1.021277 (-775 2825);
PAINT ORANGE (-775 2825);
DISPLAY INVISIBLE (-775 2825);
FORCEPROP 2 LAST SEC 1
J 0
(-775 2825);
DISPLAY 0.680851 (-775 2825);
PAINT MONO (-775 2825);
DISPLAY INVISIBLE (-775 2825);
FORCEPROP 2 LAST SEC_TYPE 0402
J 0
(-775 2825);
DISPLAY 1.021277 (-775 2825);
PAINT ORANGE (-775 2825);
DISPLAY INVISIBLE (-775 2825);
FORCEADD GND..1
(675 3125);
FORCEPROP 3 LASTPIN (675 3175) SIG_NAME GND\g
J 0
(685 3185);
DISPLAY 0.659574 (685 3185);
PAINT MONO (685 3185);
DISPLAY INVISIBLE (685 3185);
FORCEPROP 1 LAST BODY_TYPE PLUMBING
J 0
(630 3082);
DISPLAY 0.340426 (630 3082);
PAINT GREEN (630 3082);
DISPLAY INVISIBLE (630 3082);
FORCEPROP 1 LAST VOLTAGE 0
J 0
(675 3125);
DISPLAY 1.340426 (675 3125);
PAINT SKYBLUE (675 3125);
DISPLAY INVISIBLE (675 3125);
FORCEPROP 2 LAST CDS_LIB mstr_symbols
J 0
(675 3125);
DISPLAY 1.340426 (675 3125);
PAINT MONO (675 3125);
DISPLAY INVISIBLE (675 3125);
FORCEPROP 1 LAST SIZE 1B
J 0
(750 3075);
DISPLAY 1.191489 (750 3075);
PAINT GREEN (750 3075);
DISPLAY INVISIBLE (750 3075);
FORCEPROP 1 LAST PATH I19
J 0
(750 3125);
DISPLAY 0.872340 (750 3125);
PAINT AQUA (750 3125);
DISPLAY INVISIBLE (750 3125);
FORCEPROP 1 LAST HDL_POWER GND
J 0
(675 3275);
DISPLAY 1.191489 (675 3275);
PAINT GREEN (675 3275);
DISPLAY INVISIBLE (675 3275);
FORCEADD CAP..1
(3700 3875);
FORCEPROP 1 LASTPIN (3700 3775) $PN 2
J 0
(3710 3755);
DISPLAY 0.617021 (3710 3755);
PAINT WHITE (3710 3755);
FORCEPROP 1 LAST MATERIAL X6S
J 0
(3750 3775);
DISPLAY 0.617021 (3750 3775);
PAINT SKYBLUE (3750 3775);
FORCEPROP 1 LAST TOLERANCE 20%
J 0
(3750 3825);
DISPLAY 0.617021 (3750 3825);
PAINT SKYBLUE (3750 3825);
FORCEPROP 1 LAST PART_NUMBER C95333-008
R 1
J 0
(3650 3675);
DISPLAY 0.617021 (3650 3675);
PAINT BLUE (3650 3675);
FORCEPROP 1 LASTPIN (3700 3975) $PN 1
J 0
(3710 3955);
DISPLAY 0.617021 (3710 3955);
PAINT WHITE (3710 3955);
FORCEPROP 1 LAST VALUE 22UF
J 0
(3750 3925);
DISPLAY 0.617021 (3750 3925);
PAINT SKYBLUE (3750 3925);
FORCEPROP 1 LAST LOCATION C8E9
J 0
(3750 3975);
DISPLAY 0.617021 (3750 3975);
PAINT AQUA (3750 3975);
FORCEPROP 1 LAST PACK_TYPE 0805
J 0
(3750 3725);
DISPLAY 0.617021 (3750 3725);
PAINT SKYBLUE (3750 3725);
FORCEPROP 1 LAST VOLTAGE 6.3V
J 0
(3750 3875);
DISPLAY 0.617021 (3750 3875);
PAINT SKYBLUE (3750 3875);
FORCEPROP 2 LAST ROOM P5V_STBY_VR
J 0
(3750 4025);
DISPLAY 1.021277 (3750 4025);
PAINT ORANGE (3750 4025);
DISPLAY INVISIBLE (3750 4025);
FORCEPROP 1 LAST PATH I2
J 0
(3750 4025);
DISPLAY 0.978723 (3750 4025);
PAINT WHITE (3750 4025);
DISPLAY INVISIBLE (3750 4025);
FORCEPROP 2 LAST CDS_LOCATION C8E9
J 0
(3750 3975);
DISPLAY 0.617021 (3750 3975);
PAINT AQUA (3750 3975);
DISPLAY INVISIBLE (3750 3975);
FORCEPROP 2 LAST CDS_LIB mstr_discrete
J 0
(3700 3875);
DISPLAY 1.340426 (3700 3875);
PAINT ORANGE (3700 3875);
DISPLAY INVISIBLE (3700 3875);
FORCEPROP 2 LAST SEC 1
J 0
(3750 4075);
DISPLAY 0.914894 (3750 4075);
PAINT MONO (3750 4075);
DISPLAY INVISIBLE (3750 4075);
FORCEPROP 2 LAST $REUSE_ID 33
J 0
(3750 4075);
DISPLAY 1.361702 (3750 4075);
PAINT ORANGE (3750 4075);
DISPLAY INVISIBLE (3750 4075);
FORCEPROP 2 LAST BOM_COST P5V_STBY_VR
J 0
(3750 4075);
DISPLAY 1.021277 (3750 4075);
PAINT ORANGE (3750 4075);
DISPLAY INVISIBLE (3750 4075);
FORCEPROP 2 LAST SEC_TYPE 0805
J 0
(3750 4075);
DISPLAY 1.361702 (3750 4075);
PAINT ORANGE (3750 4075);
DISPLAY INVISIBLE (3750 4075);
FORCEADD CAP..1
(3325 3900);
FORCEPROP 1 LAST PART_NUMBER C95333-008
R 1
J 0
(3275 3675);
DISPLAY 0.617021 (3275 3675);
PAINT BLUE (3275 3675);
FORCEPROP 1 LASTPIN (3325 4000) $PN 1
J 0
(3335 3980);
DISPLAY 0.617021 (3335 3980);
PAINT WHITE (3335 3980);
FORCEPROP 1 LASTPIN (3325 3800) $PN 2
J 0
(3335 3780);
DISPLAY 0.617021 (3335 3780);
PAINT WHITE (3335 3780);
FORCEPROP 1 LAST VOLTAGE 6.3V
J 0
(3375 3850);
DISPLAY 0.617021 (3375 3850);
PAINT SKYBLUE (3375 3850);
FORCEPROP 1 LAST TOLERANCE 20%
J 0
(3375 3800);
DISPLAY 0.617021 (3375 3800);
PAINT SKYBLUE (3375 3800);
FORCEPROP 1 LAST VALUE 22UF
J 0
(3375 3900);
DISPLAY 0.617021 (3375 3900);
PAINT SKYBLUE (3375 3900);
FORCEPROP 1 LAST LOCATION C8E7
J 0
(3375 3950);
DISPLAY 0.617021 (3375 3950);
PAINT AQUA (3375 3950);
FORCEPROP 1 LAST MATERIAL X6S
J 0
(3375 3750);
DISPLAY 0.617021 (3375 3750);
PAINT SKYBLUE (3375 3750);
FORCEPROP 1 LAST PACK_TYPE 0805
J 0
(3375 3700);
DISPLAY 0.617021 (3375 3700);
PAINT SKYBLUE (3375 3700);
FORCEPROP 2 LAST CDS_LIB mstr_discrete
J 0
(3325 3900);
DISPLAY 1.340426 (3325 3900);
PAINT ORANGE (3325 3900);
DISPLAY INVISIBLE (3325 3900);
FORCEPROP 2 LAST ROOM P5V_STBY_VR
J 0
(3375 4000);
DISPLAY 1.021277 (3375 4000);
PAINT ORANGE (3375 4000);
DISPLAY INVISIBLE (3375 4000);
FORCEPROP 1 LAST PATH I3
J 0
(3375 4050);
DISPLAY 0.978723 (3375 4050);
PAINT WHITE (3375 4050);
DISPLAY INVISIBLE (3375 4050);
FORCEPROP 2 LAST CDS_LOCATION C8E7
J 0
(3375 3950);
DISPLAY 0.617021 (3375 3950);
PAINT AQUA (3375 3950);
DISPLAY INVISIBLE (3375 3950);
FORCEPROP 2 LAST BOM_COST P5V_STBY_VR
J 0
(3375 4050);
DISPLAY 1.021277 (3375 4050);
PAINT ORANGE (3375 4050);
DISPLAY INVISIBLE (3375 4050);
FORCEPROP 2 LAST SEC 1
J 0
(3375 4100);
DISPLAY 0.914894 (3375 4100);
PAINT MONO (3375 4100);
DISPLAY INVISIBLE (3375 4100);
FORCEPROP 2 LAST SEC_TYPE 0805
J 0
(3375 4100);
DISPLAY 1.361702 (3375 4100);
PAINT ORANGE (3375 4100);
DISPLAY INVISIBLE (3375 4100);
FORCEPROP 2 LAST REUSE_ID 33
J 0
(3375 4100);
DISPLAY 1.361702 (3375 4100);
PAINT ORANGE (3375 4100);
DISPLAY INVISIBLE (3375 4100);
FORCEADD CAP..1
(-2150 3850);
FORCEPROP 1 LASTPIN (-2150 3750) $PN 2
J 0
(-2140 3730);
DISPLAY 0.617021 (-2140 3730);
PAINT WHITE (-2140 3730);
FORCEPROP 1 LAST PART_NUMBER D97712-011
R 1
J 0
(-2200 3625);
DISPLAY 0.617021 (-2200 3625);
PAINT BLUE (-2200 3625);
FORCEPROP 1 LASTPIN (-2150 3950) $PN 1
J 0
(-2140 3930);
DISPLAY 0.617021 (-2140 3930);
PAINT WHITE (-2140 3930);
FORCEPROP 1 LAST MATERIAL X6S
J 0
(-2100 3725);
DISPLAY 0.617021 (-2100 3725);
PAINT SKYBLUE (-2100 3725);
FORCEPROP 1 LAST VOLTAGE 16V
J 0
(-2100 3825);
DISPLAY 0.617021 (-2100 3825);
PAINT SKYBLUE (-2100 3825);
FORCEPROP 1 LAST PACK_TYPE 0402
J 0
(-2100 3675);
DISPLAY 0.617021 (-2100 3675);
PAINT SKYBLUE (-2100 3675);
FORCEPROP 1 LAST TOLERANCE 10%
J 0
(-2100 3775);
DISPLAY 0.617021 (-2100 3775);
PAINT SKYBLUE (-2100 3775);
FORCEPROP 1 LAST VALUE 1.0UF
J 0
(-2100 3875);
DISPLAY 0.617021 (-2100 3875);
PAINT SKYBLUE (-2100 3875);
FORCEPROP 1 LAST LOCATION C7E14
J 0
(-2100 3925);
DISPLAY 0.617021 (-2100 3925);
PAINT AQUA (-2100 3925);
FORCEPROP 2 LAST CDS_LOCATION C7E14
J 0
(-2100 3925);
DISPLAY 0.617021 (-2100 3925);
PAINT AQUA (-2100 3925);
DISPLAY INVISIBLE (-2100 3925);
FORCEPROP 2 LAST CDS_LIB mstr_discrete
J 0
(-2150 3850);
DISPLAY 1.340426 (-2150 3850);
PAINT ORANGE (-2150 3850);
DISPLAY INVISIBLE (-2150 3850);
FORCEPROP 2 LAST BOM_COST P5V_STBY_VR
J 0
(-2100 4025);
DISPLAY 1.021277 (-2100 4025);
PAINT ORANGE (-2100 4025);
DISPLAY INVISIBLE (-2100 4025);
FORCEPROP 2 LAST SEC 1
J 0
(-2100 4050);
DISPLAY 0.914894 (-2100 4050);
PAINT MONO (-2100 4050);
DISPLAY INVISIBLE (-2100 4050);
FORCEPROP 1 LAST PATH I30
J 0
(-2100 4000);
DISPLAY 0.978723 (-2100 4000);
PAINT WHITE (-2100 4000);
DISPLAY INVISIBLE (-2100 4000);
FORCEPROP 2 LAST ROOM P5V_STBY_VR
J 0
(-2100 3975);
DISPLAY 1.021277 (-2100 3975);
PAINT ORANGE (-2100 3975);
DISPLAY INVISIBLE (-2100 3975);
FORCEPROP 2 LAST SEC_TYPE 0402
J 0
(-2100 4050);
DISPLAY 1.361702 (-2100 4050);
PAINT ORANGE (-2100 4050);
DISPLAY INVISIBLE (-2100 4050);
FORCEPROP 0 LAST REUSE_ID 1
J 0
(-2100 4050);
DISPLAY 1.361702 (-2100 4050);
PAINT ORANGE (-2100 4050);
DISPLAY INVISIBLE (-2100 4050);
FORCEPROP 0 LAST FIN VR_1P2
J 0
(-2100 4150);
DISPLAY 1.340426 (-2100 4150);
PAINT ORANGE (-2100 4150);
DISPLAY INVISIBLE (-2100 4150);
FORCEADD GND..1
(-2150 3550);
FORCEPROP 3 LASTPIN (-2150 3600) SIG_NAME GND\g
J 0
(-2140 3610);
DISPLAY 0.659574 (-2140 3610);
PAINT MONO (-2140 3610);
DISPLAY INVISIBLE (-2140 3610);
FORCEPROP 1 LAST BODY_TYPE PLUMBING
J 0
(-2195 3507);
DISPLAY 0.340426 (-2195 3507);
PAINT GREEN (-2195 3507);
DISPLAY INVISIBLE (-2195 3507);
FORCEPROP 1 LAST SIZE 1B
J 0
(-2075 3500);
DISPLAY 1.170213 (-2075 3500);
PAINT GREEN (-2075 3500);
DISPLAY INVISIBLE (-2075 3500);
FORCEPROP 1 LAST PATH I31
J 0
(-2075 3550);
DISPLAY 0.872340 (-2075 3550);
PAINT AQUA (-2075 3550);
DISPLAY INVISIBLE (-2075 3550);
FORCEPROP 2 LAST CDS_LIB mstr_symbols
J 0
(-2150 3550);
DISPLAY 1.340426 (-2150 3550);
PAINT MONO (-2150 3550);
DISPLAY INVISIBLE (-2150 3550);
FORCEPROP 1 LAST VOLTAGE 0
J 0
(-2150 3550);
DISPLAY 1.340426 (-2150 3550);
PAINT SKYBLUE (-2150 3550);
DISPLAY INVISIBLE (-2150 3550);
FORCEPROP 1 LAST HDL_POWER GND
J 0
(-2150 3700);
DISPLAY 1.170213 (-2150 3700);
PAINT GREEN (-2150 3700);
DISPLAY INVISIBLE (-2150 3700);
FORCEADD GND..1
(-2000 2700);
FORCEPROP 3 LASTPIN (-2000 2750) SIG_NAME AGND_P5V_STBY\g
J 0
(-1990 2760);
DISPLAY 0.659574 (-1990 2760);
PAINT MONO (-1990 2760);
DISPLAY INVISIBLE (-1990 2760);
FORCEPROP 1 LAST HDL_POWER AGND_P5V_STBY
J 0
(-2275 2650);
DISPLAY 0.617021 (-2275 2650);
PAINT GREEN (-2275 2650);
FORCEPROP 1 LAST PATH I32
J 0
(-1925 2700);
DISPLAY 0.872340 (-1925 2700);
PAINT AQUA (-1925 2700);
DISPLAY INVISIBLE (-1925 2700);
FORCEPROP 1 LAST BODY_TYPE PLUMBING
J 0
(-2045 2657);
DISPLAY 0.340426 (-2045 2657);
PAINT GREEN (-2045 2657);
DISPLAY INVISIBLE (-2045 2657);
FORCEPROP 2 LAST CDS_LIB mstr_symbols
J 0
(-2000 2700);
PAINT MONO (-2000 2700);
DISPLAY INVISIBLE (-2000 2700);
FORCEPROP 1 LAST SIZE 1B
J 0
(-1925 2650);
DISPLAY 1.170213 (-1925 2650);
PAINT AQUA (-1925 2650);
DISPLAY INVISIBLE (-1925 2650);
FORCEPROP 1 LAST VOLTAGE 0
J 0
(-2000 2700);
DISPLAY 1.340426 (-2000 2700);
PAINT SKYBLUE (-2000 2700);
DISPLAY INVISIBLE (-2000 2700);
FORCEADD RES..2
(-2150 4200);
FORCEPROP 1 LAST PACK_TYPE 0402
J 0
(-2110 4075);
DISPLAY 0.617021 (-2110 4075);
PAINT SKYBLUE (-2110 4075);
FORCEPROP 1 LAST PART_NUMBER G21497-005
R 1
J 0
(-2185 4050);
DISPLAY 0.617021 (-2185 4050);
PAINT BLUE (-2185 4050);
FORCEPROP 1 LASTPIN (-2150 4100) $PN 2
J 0
(-2145 4110);
DISPLAY 0.617021 (-2145 4110);
PAINT WHITE (-2145 4110);
FORCEPROP 1 LASTPIN (-2150 4300) $PN 1
J 0
(-2145 4262);
DISPLAY 0.617021 (-2145 4262);
PAINT WHITE (-2145 4262);
FORCEPROP 1 LAST WATTAGE 1/16W
J 0
(-2110 4175);
DISPLAY 0.617021 (-2110 4175);
PAINT SKYBLUE (-2110 4175);
FORCEPROP 1 LAST MATERIAL CHIP
J 0
(-2110 4125);
DISPLAY 0.617021 (-2110 4125);
PAINT SKYBLUE (-2110 4125);
FORCEPROP 1 LAST TOLERANCE 5%
J 0
(-2105 4225);
DISPLAY 0.617021 (-2105 4225);
PAINT SKYBLUE (-2105 4225);
FORCEPROP 1 LAST VALUE 0.0
J 0
(-2105 4275);
DISPLAY 0.617021 (-2105 4275);
PAINT SKYBLUE (-2105 4275);
FORCEPROP 1 LAST LOCATION R7E17
J 0
(-2105 4325);
DISPLAY 0.617021 (-2105 4325);
PAINT AQUA (-2105 4325);
FORCEPROP 2 LAST CDS_LIB mstr_discrete
J 0
(-2150 4200);
DISPLAY 1.340426 (-2150 4200);
PAINT ORANGE (-2150 4200);
DISPLAY INVISIBLE (-2150 4200);
FORCEPROP 2 LAST CDS_LOCATION R7E17
J 0
(-2105 4325);
DISPLAY 0.617021 (-2105 4325);
PAINT AQUA (-2105 4325);
DISPLAY INVISIBLE (-2105 4325);
FORCEPROP 2 LAST SEC 1
J 0
(-2100 4425);
DISPLAY 0.914894 (-2100 4425);
PAINT MONO (-2100 4425);
DISPLAY INVISIBLE (-2100 4425);
FORCEPROP 2 LAST BOM_COST P5V_STBY_VR
J 0
(-2100 4425);
DISPLAY 1.021277 (-2100 4425);
PAINT ORANGE (-2100 4425);
DISPLAY INVISIBLE (-2100 4425);
FORCEPROP 1 LAST PATH I37
J 0
(-2100 4375);
DISPLAY 0.978723 (-2100 4375);
PAINT WHITE (-2100 4375);
DISPLAY INVISIBLE (-2100 4375);
FORCEPROP 2 LAST ROOM P5V_STBY_VR
J 0
(-2100 4375);
DISPLAY 1.021277 (-2100 4375);
PAINT ORANGE (-2100 4375);
DISPLAY INVISIBLE (-2100 4375);
FORCEPROP 2 LAST SEC_TYPE 0402
J 0
(-2100 4425);
DISPLAY 1.361702 (-2100 4425);
PAINT ORANGE (-2100 4425);
DISPLAY INVISIBLE (-2100 4425);
FORCEPROP 2 LAST $REUSE_ID 13
J 0
(-2100 4425);
DISPLAY 1.361702 (-2100 4425);
PAINT ORANGE (-2100 4425);
DISPLAY INVISIBLE (-2100 4425);
FORCEPROP 2 LAST NO_XNET_CONNECTION 1
J 0
(-2100 4425);
PAINT MONO (-2100 4425);
DISPLAY INVISIBLE (-2100 4425);
FORCEADD CAP..1
(-2550 4250);
FORCEPROP 1 LAST PACK_TYPE 1206LF
J 0
(-2500 4050);
DISPLAY 0.617021 (-2500 4050);
PAINT SKYBLUE (-2500 4050);
FORCEPROP 1 LAST PART_NUMBER D38464-005
R 1
J 0
(-2600 4075);
DISPLAY 0.617021 (-2600 4075);
PAINT BLUE (-2600 4075);
FORCEPROP 1 LAST VOLTAGE 16V
J 0
(-2500 4200);
DISPLAY 0.617021 (-2500 4200);
PAINT SKYBLUE (-2500 4200);
FORCEPROP 1 LAST MATERIAL X6S
J 0
(-2500 4100);
DISPLAY 0.617021 (-2500 4100);
PAINT SKYBLUE (-2500 4100);
FORCEPROP 1 LASTPIN (-2550 4150) $PN 2
J 0
(-2540 4130);
DISPLAY 0.617021 (-2540 4130);
PAINT WHITE (-2540 4130);
FORCEPROP 1 LAST VALUE 22UF
J 0
(-2500 4250);
DISPLAY 0.617021 (-2500 4250);
PAINT SKYBLUE (-2500 4250);
FORCEPROP 1 LAST LOCATION C7E11
J 0
(-2500 4300);
DISPLAY 0.617021 (-2500 4300);
PAINT AQUA (-2500 4300);
FORCEPROP 1 LAST TOLERANCE 10%
J 0
(-2500 4150);
DISPLAY 0.617021 (-2500 4150);
PAINT SKYBLUE (-2500 4150);
FORCEPROP 1 LASTPIN (-2550 4350) $PN 1
J 0
(-2540 4330);
DISPLAY 0.617021 (-2540 4330);
PAINT WHITE (-2540 4330);
FORCEPROP 2 LAST CDS_LOCATION C7E11
J 0
(-2500 4300);
DISPLAY 0.617021 (-2500 4300);
PAINT AQUA (-2500 4300);
DISPLAY INVISIBLE (-2500 4300);
FORCEPROP 2 LAST CDS_LIB mstr_discrete
J 0
(-2550 4250);
DISPLAY 1.340426 (-2550 4250);
PAINT ORANGE (-2550 4250);
DISPLAY INVISIBLE (-2550 4250);
FORCEPROP 2 LAST ROOM P5V_STBY_VR
J 0
(-2500 4350);
DISPLAY 1.021277 (-2500 4350);
PAINT ORANGE (-2500 4350);
DISPLAY INVISIBLE (-2500 4350);
FORCEPROP 2 LAST SEC 1
J 0
(-2500 4450);
DISPLAY 0.680851 (-2500 4450);
PAINT MONO (-2500 4450);
DISPLAY INVISIBLE (-2500 4450);
FORCEPROP 1 LAST PATH I39
J 0
(-2500 4400);
DISPLAY 0.978723 (-2500 4400);
PAINT WHITE (-2500 4400);
DISPLAY INVISIBLE (-2500 4400);
FORCEPROP 2 LAST SEC_TYPE 1206LF
J 0
(-2500 4450);
DISPLAY 1.021277 (-2500 4450);
PAINT ORANGE (-2500 4450);
DISPLAY INVISIBLE (-2500 4450);
FORCEPROP 2 LAST BOM_COST P5V_STBY_VR
J 0
(-2500 4400);
DISPLAY 1.021277 (-2500 4400);
PAINT ORANGE (-2500 4400);
DISPLAY INVISIBLE (-2500 4400);
FORCEADD GND..1
(3600 3475);
FORCEPROP 3 LASTPIN (3600 3525) SIG_NAME GND\g
J 0
(3610 3535);
DISPLAY 0.659574 (3610 3535);
PAINT MONO (3610 3535);
DISPLAY INVISIBLE (3610 3535);
FORCEPROP 1 LAST BODY_TYPE PLUMBING
J 0
(3555 3432);
DISPLAY 0.340426 (3555 3432);
PAINT GREEN (3555 3432);
DISPLAY INVISIBLE (3555 3432);
FORCEPROP 1 LAST PATH I4
J 0
(3675 3475);
DISPLAY 0.872340 (3675 3475);
PAINT AQUA (3675 3475);
DISPLAY INVISIBLE (3675 3475);
FORCEPROP 2 LAST CDS_LIB mstr_symbols
J 0
(3600 3475);
DISPLAY 1.340426 (3600 3475);
PAINT MONO (3600 3475);
DISPLAY INVISIBLE (3600 3475);
FORCEPROP 1 LAST SIZE 1B
J 0
(3675 3425);
DISPLAY 1.170213 (3675 3425);
PAINT GREEN (3675 3425);
DISPLAY INVISIBLE (3675 3425);
FORCEPROP 1 LAST VOLTAGE 0
J 0
(3600 3475);
DISPLAY 1.340426 (3600 3475);
PAINT SKYBLUE (3600 3475);
DISPLAY INVISIBLE (3600 3475);
FORCEPROP 1 LAST HDL_POWER GND
J 0
(3600 3625);
DISPLAY 1.170213 (3600 3625);
PAINT GREEN (3600 3625);
DISPLAY INVISIBLE (3600 3625);
FORCEADD GND..1
(-2550 4025);
FORCEPROP 3 LASTPIN (-2550 4075) SIG_NAME GND\g
J 0
(-2540 4085);
DISPLAY 0.659574 (-2540 4085);
PAINT MONO (-2540 4085);
DISPLAY INVISIBLE (-2540 4085);
FORCEPROP 1 LAST BODY_TYPE PLUMBING
J 0
(-2595 3982);
DISPLAY 0.340426 (-2595 3982);
PAINT GREEN (-2595 3982);
DISPLAY INVISIBLE (-2595 3982);
FORCEPROP 1 LAST PATH I40
J 0
(-2475 4025);
DISPLAY 0.872340 (-2475 4025);
PAINT AQUA (-2475 4025);
DISPLAY INVISIBLE (-2475 4025);
FORCEPROP 1 LAST SIZE 1B
J 0
(-2475 3975);
DISPLAY 1.170213 (-2475 3975);
PAINT GREEN (-2475 3975);
DISPLAY INVISIBLE (-2475 3975);
FORCEPROP 1 LAST VOLTAGE 0
J 0
(-2550 4025);
DISPLAY 1.340426 (-2550 4025);
PAINT SKYBLUE (-2550 4025);
DISPLAY INVISIBLE (-2550 4025);
FORCEPROP 2 LAST CDS_LIB mstr_symbols
J 0
(-2550 4025);
DISPLAY 1.340426 (-2550 4025);
PAINT MONO (-2550 4025);
DISPLAY INVISIBLE (-2550 4025);
FORCEPROP 1 LAST HDL_POWER GND
J 0
(-2550 4175);
DISPLAY 1.170213 (-2550 4175);
PAINT GREEN (-2550 4175);
DISPLAY INVISIBLE (-2550 4175);
FORCEADD CAP..1
R 2
(-2000 3075);
FORCEPROP 1 LAST VOLTAGE 50V
J 2
(-2050 3025);
DISPLAY 0.617021 (-2050 3025);
PAINT SKYBLUE (-2050 3025);
FORCEPROP 1 LAST PACK_TYPE 0402LF
J 2
(-2050 2875);
DISPLAY 0.617021 (-2050 2875);
PAINT SKYBLUE (-2050 2875);
FORCEPROP 1 LAST TOLERANCE 10%
J 2
(-2050 2975);
DISPLAY 0.617021 (-2050 2975);
PAINT SKYBLUE (-2050 2975);
FORCEPROP 1 LAST MATERIAL EMPTY
J 2
(-2050 2925);
DISPLAY 0.617021 (-2050 2925);
PAINT RED (-2050 2925);
FORCEPROP 1 LAST VALUE 1000PF
J 2
(-2050 3075);
DISPLAY 0.617021 (-2050 3075);
PAINT SKYBLUE (-2050 3075);
FORCEPROP 1 LAST LOCATION C8E13
J 2
(-2075 3125);
DISPLAY 0.617021 (-2075 3125);
PAINT AQUA (-2075 3125);
FORCEPROP 1 LASTPIN (-2000 2975) $PN 2
J 2
(-2010 2955);
DISPLAY 0.617021 (-2010 2955);
PAINT WHITE (-2010 2955);
FORCEPROP 1 LAST PART_NUMBER A36096-046
R 1
J 2
(-1925 3250);
DISPLAY 0.617021 (-1925 3250);
PAINT BLUE (-1925 3250);
FORCEPROP 1 LASTPIN (-2000 3175) $PN 1
J 2
(-2010 3155);
DISPLAY 0.617021 (-2010 3155);
PAINT WHITE (-2010 3155);
FORCEPROP 2 LAST ROOM P5V_STBY_VR
J 0
(-2075 3175);
DISPLAY 1.021277 (-2075 3175);
PAINT ORANGE (-2075 3175);
DISPLAY INVISIBLE (-2075 3175);
FORCEPROP 1 LAST PATH I41
J 2
(-2050 3225);
DISPLAY 0.978723 (-2050 3225);
PAINT WHITE (-2050 3225);
DISPLAY INVISIBLE (-2050 3225);
FORCEPROP 2 LAST CDS_LOCATION C8E13
J 2
(-2075 3125);
DISPLAY 0.617021 (-2075 3125);
PAINT AQUA (-2075 3125);
DISPLAY INVISIBLE (-2075 3125);
FORCEPROP 2 LAST SEC 1
J 0
(-2050 3275);
DISPLAY 0.914894 (-2050 3275);
PAINT MONO (-2050 3275);
DISPLAY INVISIBLE (-2050 3275);
FORCEPROP 2 LAST BOM_COST P5V_STBY_VR
J 0
(-2075 3225);
DISPLAY 1.021277 (-2075 3225);
PAINT ORANGE (-2075 3225);
DISPLAY INVISIBLE (-2075 3225);
FORCEPROP 0 LAST REUSE_ID 1
J 2
(-2050 3275);
DISPLAY 1.361702 (-2050 3275);
PAINT ORANGE (-2050 3275);
DISPLAY INVISIBLE (-2050 3275);
FORCEPROP 2 LAST SEC_TYPE 0402LF
J 0
(-2050 3275);
DISPLAY 1.361702 (-2050 3275);
PAINT ORANGE (-2050 3275);
DISPLAY INVISIBLE (-2050 3275);
FORCEPROP 0 LAST FIN VR_1P2
J 2
(-2050 3375);
DISPLAY 1.340426 (-2050 3375);
PAINT ORANGE (-2050 3375);
DISPLAY INVISIBLE (-2050 3375);
FORCEPROP 2 LAST CDS_LIB mstr_discrete
J 0
(-2000 3075);
DISPLAY 1.340426 (-2000 3075);
PAINT ORANGE (-2000 3075);
DISPLAY INVISIBLE (-2000 3075);
FORCEADD GND..1
(-2875 4025);
FORCEPROP 3 LASTPIN (-2875 4075) SIG_NAME GND\g
J 0
(-2865 4085);
DISPLAY 0.659574 (-2865 4085);
PAINT MONO (-2865 4085);
DISPLAY INVISIBLE (-2865 4085);
FORCEPROP 1 LAST PATH I44
J 0
(-2800 4025);
DISPLAY 0.872340 (-2800 4025);
PAINT AQUA (-2800 4025);
DISPLAY INVISIBLE (-2800 4025);
FORCEPROP 1 LAST BODY_TYPE PLUMBING
J 0
(-2920 3982);
DISPLAY 0.340426 (-2920 3982);
PAINT GREEN (-2920 3982);
DISPLAY INVISIBLE (-2920 3982);
FORCEPROP 1 LAST SIZE 1B
J 0
(-2800 3975);
DISPLAY 1.170213 (-2800 3975);
PAINT GREEN (-2800 3975);
DISPLAY INVISIBLE (-2800 3975);
FORCEPROP 2 LAST CDS_LIB mstr_symbols
J 0
(-2875 4025);
DISPLAY 1.340426 (-2875 4025);
PAINT MONO (-2875 4025);
DISPLAY INVISIBLE (-2875 4025);
FORCEPROP 1 LAST VOLTAGE 0
J 0
(-2875 4025);
DISPLAY 1.340426 (-2875 4025);
PAINT SKYBLUE (-2875 4025);
DISPLAY INVISIBLE (-2875 4025);
FORCEPROP 1 LAST HDL_POWER GND
J 0
(-2875 4175);
DISPLAY 1.170213 (-2875 4175);
PAINT GREEN (-2875 4175);
DISPLAY INVISIBLE (-2875 4175);
FORCEADD CAP..1
(-2875 4275);
FORCEPROP 1 LAST PACK_TYPE 1210
J 0
(-2825 4075);
DISPLAY 0.617021 (-2825 4075);
PAINT SKYBLUE (-2825 4075);
FORCEPROP 1 LASTPIN (-2875 4175) $PN 2
J 0
(-2865 4155);
DISPLAY 0.617021 (-2865 4155);
PAINT WHITE (-2865 4155);
FORCEPROP 1 LASTPIN (-2875 4375) $PN 1
J 0
(-2865 4355);
DISPLAY 0.617021 (-2865 4355);
PAINT WHITE (-2865 4355);
FORCEPROP 1 LAST MATERIAL X6S
J 0
(-2825 4125);
DISPLAY 0.617021 (-2825 4125);
PAINT SKYBLUE (-2825 4125);
FORCEPROP 1 LAST VOLTAGE 16V
J 0
(-2825 4225);
DISPLAY 0.617021 (-2825 4225);
PAINT SKYBLUE (-2825 4225);
FORCEPROP 1 LAST TOLERANCE 20%
J 0
(-2825 4175);
DISPLAY 0.617021 (-2825 4175);
PAINT SKYBLUE (-2825 4175);
FORCEPROP 1 LAST VALUE 47UF
J 0
(-2825 4275);
DISPLAY 0.617021 (-2825 4275);
PAINT SKYBLUE (-2825 4275);
FORCEPROP 1 LAST LOCATION C7E13
J 0
(-2825 4325);
DISPLAY 0.617021 (-2825 4325);
PAINT AQUA (-2825 4325);
FORCEPROP 1 LAST PART_NUMBER D38464-007
R 1
J 0
(-2925 4075);
DISPLAY 0.617021 (-2925 4075);
PAINT BLUE (-2925 4075);
FORCEPROP 2 LAST CDS_LIB mstr_discrete
J 0
(-2875 4275);
DISPLAY 1.340426 (-2875 4275);
PAINT ORANGE (-2875 4275);
DISPLAY INVISIBLE (-2875 4275);
FORCEPROP 2 LAST CDS_LOCATION C7E13
J 0
(-2825 4325);
DISPLAY 0.617021 (-2825 4325);
PAINT AQUA (-2825 4325);
DISPLAY INVISIBLE (-2825 4325);
FORCEPROP 2 LAST SEC_TYPE 1210
J 0
(-2825 4475);
DISPLAY 1.021277 (-2825 4475);
PAINT ORANGE (-2825 4475);
DISPLAY INVISIBLE (-2825 4475);
FORCEPROP 2 LAST BOM_COST P5V_STBY_VR
J 0
(-2825 4425);
DISPLAY 1.021277 (-2825 4425);
PAINT ORANGE (-2825 4425);
DISPLAY INVISIBLE (-2825 4425);
FORCEPROP 2 LAST SEC 1
J 0
(-2825 4475);
DISPLAY 0.680851 (-2825 4475);
PAINT MONO (-2825 4475);
DISPLAY INVISIBLE (-2825 4475);
FORCEPROP 1 LAST PATH I45
J 0
(-2825 4425);
DISPLAY 0.978723 (-2825 4425);
PAINT WHITE (-2825 4425);
DISPLAY INVISIBLE (-2825 4425);
FORCEPROP 2 LAST ROOM P5V_STBY_VR
J 0
(-2825 4375);
DISPLAY 1.021277 (-2825 4375);
PAINT ORANGE (-2825 4375);
DISPLAY INVISIBLE (-2825 4375);
FORCEADD GND..1
(-3225 4025);
FORCEPROP 3 LASTPIN (-3225 4075) SIG_NAME GND\g
J 0
(-3215 4085);
DISPLAY 0.659574 (-3215 4085);
PAINT MONO (-3215 4085);
DISPLAY INVISIBLE (-3215 4085);
FORCEPROP 1 LAST PATH I46
J 0
(-3150 4025);
DISPLAY 0.872340 (-3150 4025);
PAINT AQUA (-3150 4025);
DISPLAY INVISIBLE (-3150 4025);
FORCEPROP 1 LAST BODY_TYPE PLUMBING
J 0
(-3270 3982);
DISPLAY 0.340426 (-3270 3982);
PAINT GREEN (-3270 3982);
DISPLAY INVISIBLE (-3270 3982);
FORCEPROP 2 LAST CDS_LIB mstr_symbols
J 0
(-3225 4025);
DISPLAY 1.340426 (-3225 4025);
PAINT MONO (-3225 4025);
DISPLAY INVISIBLE (-3225 4025);
FORCEPROP 1 LAST SIZE 1B
J 0
(-3150 3975);
DISPLAY 1.170213 (-3150 3975);
PAINT GREEN (-3150 3975);
DISPLAY INVISIBLE (-3150 3975);
FORCEPROP 1 LAST VOLTAGE 0
J 0
(-3225 4025);
DISPLAY 1.340426 (-3225 4025);
PAINT SKYBLUE (-3225 4025);
DISPLAY INVISIBLE (-3225 4025);
FORCEPROP 1 LAST HDL_POWER GND
J 0
(-3225 4175);
DISPLAY 1.170213 (-3225 4175);
PAINT GREEN (-3225 4175);
DISPLAY INVISIBLE (-3225 4175);
FORCEADD CAP..1
(-3225 4275);
FORCEPROP 1 LAST PART_NUMBER D38464-007
R 1
J 0
(-3275 4075);
DISPLAY 0.617021 (-3275 4075);
PAINT BLUE (-3275 4075);
FORCEPROP 1 LASTPIN (-3225 4175) $PN 2
J 0
(-3215 4155);
DISPLAY 0.617021 (-3215 4155);
PAINT WHITE (-3215 4155);
FORCEPROP 1 LAST VOLTAGE 16V
J 0
(-3175 4225);
DISPLAY 0.617021 (-3175 4225);
PAINT SKYBLUE (-3175 4225);
FORCEPROP 1 LAST TOLERANCE 20%
J 0
(-3175 4175);
DISPLAY 0.617021 (-3175 4175);
PAINT SKYBLUE (-3175 4175);
FORCEPROP 1 LASTPIN (-3225 4375) $PN 1
J 0
(-3215 4355);
DISPLAY 0.617021 (-3215 4355);
PAINT WHITE (-3215 4355);
FORCEPROP 1 LAST VALUE 47UF
J 0
(-3175 4300);
DISPLAY 0.617021 (-3175 4300);
PAINT SKYBLUE (-3175 4300);
FORCEPROP 1 LAST LOCATION C7E12
J 0
(-3175 4375);
DISPLAY 0.617021 (-3175 4375);
PAINT AQUA (-3175 4375);
FORCEPROP 1 LAST PACK_TYPE 1210
J 0
(-3175 4075);
DISPLAY 0.617021 (-3175 4075);
PAINT SKYBLUE (-3175 4075);
FORCEPROP 1 LAST MATERIAL X6S
J 0
(-3175 4125);
DISPLAY 0.617021 (-3175 4125);
PAINT SKYBLUE (-3175 4125);
FORCEPROP 2 LAST CDS_LIB mstr_discrete
J 0
(-3225 4275);
DISPLAY 1.340426 (-3225 4275);
PAINT ORANGE (-3225 4275);
DISPLAY INVISIBLE (-3225 4275);
FORCEPROP 2 LAST CDS_LOCATION C7E12
J 0
(-3175 4375);
DISPLAY 0.617021 (-3175 4375);
PAINT AQUA (-3175 4375);
DISPLAY INVISIBLE (-3175 4375);
FORCEPROP 1 LAST PATH I47
J 0
(-3175 4425);
DISPLAY 0.978723 (-3175 4425);
PAINT WHITE (-3175 4425);
DISPLAY INVISIBLE (-3175 4425);
FORCEPROP 2 LAST ROOM P5V_STBY_VR
J 0
(-3175 4425);
DISPLAY 1.021277 (-3175 4425);
PAINT ORANGE (-3175 4425);
DISPLAY INVISIBLE (-3175 4425);
FORCEPROP 2 LAST SEC_TYPE 1210
J 0
(-3175 4475);
DISPLAY 1.021277 (-3175 4475);
PAINT ORANGE (-3175 4475);
DISPLAY INVISIBLE (-3175 4475);
FORCEPROP 2 LAST BOM_COST P5V_STBY_VR
J 0
(-3175 4475);
DISPLAY 1.021277 (-3175 4475);
PAINT ORANGE (-3175 4475);
DISPLAY INVISIBLE (-3175 4475);
FORCEPROP 2 LAST SEC 1
J 0
(-3175 4475);
DISPLAY 0.680851 (-3175 4475);
PAINT MONO (-3175 4475);
DISPLAY INVISIBLE (-3175 4475);
FORCEADD OFFPAGE..1
(-3300 3475);
FORCEPROP 2 LAST $XR0 196 
J 0
(-3552 3475);
DISPLAY 0.638298 (-3552 3475);
PAINT MONO (-3552 3475);
FORCEPROP 2 LAST $XR1 181 
J 0
(-3672 3475);
DISPLAY 0.638298 (-3672 3475);
PAINT MONO (-3672 3475);
FORCEPROP 2 LAST PATH I48
J 0
(-3725 3525);
DISPLAY 1.021277 (-3725 3525);
PAINT ORANGE (-3725 3525);
DISPLAY INVISIBLE (-3725 3525);
FORCEPROP 1 LAST COMMENT_BODY TRUE
J 0
(-3175 3375);
DISPLAY 1.170213 (-3175 3375);
PAINT GREEN (-3175 3375);
DISPLAY INVISIBLE (-3175 3375);
FORCEPROP 2 LAST CDS_LIB mstr_standard
J 0
(-3300 3475);
PAINT MONO (-3300 3475);
DISPLAY INVISIBLE (-3300 3475);
FORCEPROP 1 LAST OFFPAGE TRUE
J 0
(-2975 3350);
DISPLAY 1.170213 (-2975 3350);
PAINT GREEN (-2975 3350);
DISPLAY INVISIBLE (-2975 3350);
FORCEADD RES..2
(1750 3425);
FORCEPROP 1 LAST PART_NUMBER G21796-016
R 1
J 0
(1715 3200);
DISPLAY 0.617021 (1715 3200);
PAINT BLUE (1715 3200);
FORCEPROP 1 LASTPIN (1750 3325) $PN 2
J 0
(1755 3335);
DISPLAY 0.617021 (1755 3335);
PAINT WHITE (1755 3335);
FORCEPROP 1 LASTPIN (1750 3525) $PN 1
J 0
(1755 3487);
DISPLAY 0.617021 (1755 3487);
PAINT WHITE (1755 3487);
FORCEPROP 1 LAST WATTAGE 1/16W
J 0
(1790 3375);
DISPLAY 0.617021 (1790 3375);
PAINT SKYBLUE (1790 3375);
FORCEPROP 1 LAST MATERIAL CHIP
J 0
(1790 3300);
DISPLAY 0.617021 (1790 3300);
PAINT SKYBLUE (1790 3300);
FORCEPROP 1 LAST PACK_TYPE 0402
J 0
(1790 3250);
DISPLAY 0.617021 (1790 3250);
PAINT SKYBLUE (1790 3250);
FORCEPROP 1 LAST TOLERANCE 1%
J 0
(1795 3425);
DISPLAY 0.617021 (1795 3425);
PAINT SKYBLUE (1795 3425);
FORCEPROP 1 LAST VALUE 10.0K
J 0
(1795 3475);
DISPLAY 0.617021 (1795 3475);
PAINT SKYBLUE (1795 3475);
FORCEPROP 1 LAST LOCATION R7F1
J 0
(1795 3550);
DISPLAY 0.617021 (1795 3550);
PAINT AQUA (1795 3550);
FORCEPROP 2 LAST CDS_LIB mstr_discrete
J 0
(1750 3425);
DISPLAY 1.340426 (1750 3425);
PAINT ORANGE (1750 3425);
DISPLAY INVISIBLE (1750 3425);
FORCEPROP 2 LAST CDS_LOCATION R7F1
J 0
(1795 3550);
DISPLAY 0.617021 (1795 3550);
PAINT AQUA (1795 3550);
DISPLAY INVISIBLE (1795 3550);
FORCEPROP 2 LAST SEC_TYPE 0402
J 0
(1800 3650);
DISPLAY 1.361702 (1800 3650);
PAINT ORANGE (1800 3650);
DISPLAY INVISIBLE (1800 3650);
FORCEPROP 2 LAST REUSE_ID 9
J 0
(1800 3650);
DISPLAY 1.361702 (1800 3650);
PAINT ORANGE (1800 3650);
DISPLAY INVISIBLE (1800 3650);
FORCEPROP 2 LAST ROOM P5V_STBY_VR
J 0
(1800 3600);
DISPLAY 1.021277 (1800 3600);
PAINT ORANGE (1800 3600);
DISPLAY INVISIBLE (1800 3600);
FORCEPROP 2 LAST SEC 1
J 0
(1800 3650);
DISPLAY 0.914894 (1800 3650);
PAINT MONO (1800 3650);
DISPLAY INVISIBLE (1800 3650);
FORCEPROP 1 LAST PATH I50
J 0
(1800 3600);
DISPLAY 0.978723 (1800 3600);
PAINT WHITE (1800 3600);
DISPLAY INVISIBLE (1800 3600);
FORCEPROP 2 LAST SPOF TRUE
J 0
(1795 3605);
DISPLAY 1.340426 (1795 3605);
PAINT MONO (1795 3605);
DISPLAY INVISIBLE (1795 3605);
FORCEPROP 2 LAST BOM_COST P5V_STBY_VR
J 0
(1800 3650);
DISPLAY 1.021277 (1800 3650);
PAINT ORANGE (1800 3650);
DISPLAY INVISIBLE (1800 3650);
FORCEADD RES..2
(1750 2900);
FORCEPROP 1 LASTPIN (1750 2800) $PN 2
J 0
(1755 2810);
DISPLAY 0.617021 (1755 2810);
PAINT WHITE (1755 2810);
FORCEPROP 1 LAST PART_NUMBER G21796-095
R 1
J 0
(1715 2725);
DISPLAY 0.617021 (1715 2725);
PAINT BLUE (1715 2725);
FORCEPROP 1 LASTPIN (1750 3000) $PN 1
J 0
(1755 2962);
DISPLAY 0.617021 (1755 2962);
PAINT WHITE (1755 2962);
FORCEPROP 1 LAST WATTAGE 1/16W
J 0
(1790 2850);
DISPLAY 0.617021 (1790 2850);
PAINT SKYBLUE (1790 2850);
FORCEPROP 1 LAST MATERIAL CHIP
J 0
(1790 2775);
DISPLAY 0.617021 (1790 2775);
PAINT SKYBLUE (1790 2775);
FORCEPROP 1 LAST PACK_TYPE 0402
J 0
(1790 2725);
DISPLAY 0.617021 (1790 2725);
PAINT SKYBLUE (1790 2725);
FORCEPROP 1 LAST TOLERANCE 1%
J 0
(1795 2900);
DISPLAY 0.617021 (1795 2900);
PAINT SKYBLUE (1795 2900);
FORCEPROP 1 LAST VALUE 1.37K
J 0
(1795 2950);
DISPLAY 0.617021 (1795 2950);
PAINT SKYBLUE (1795 2950);
FORCEPROP 1 LAST LOCATION R7E16
J 0
(1795 3000);
DISPLAY 0.617021 (1795 3000);
PAINT AQUA (1795 3000);
FORCEPROP 2 LAST CDS_LIB mstr_discrete
J 0
(1750 2900);
DISPLAY 1.340426 (1750 2900);
PAINT ORANGE (1750 2900);
DISPLAY INVISIBLE (1750 2900);
FORCEPROP 2 LAST CDS_LOCATION R7E16
J 0
(1795 3000);
DISPLAY 0.617021 (1795 3000);
PAINT AQUA (1795 3000);
DISPLAY INVISIBLE (1795 3000);
FORCEPROP 2 LAST ROOM P5V_STBY_VR
J 0
(1800 3050);
DISPLAY 1.021277 (1800 3050);
PAINT ORANGE (1800 3050);
DISPLAY INVISIBLE (1800 3050);
FORCEPROP 1 LAST PATH I51
J 0
(1800 3075);
DISPLAY 0.978723 (1800 3075);
PAINT WHITE (1800 3075);
DISPLAY INVISIBLE (1800 3075);
FORCEPROP 2 LAST SEC 1
J 0
(1800 3125);
DISPLAY 0.914894 (1800 3125);
PAINT MONO (1800 3125);
DISPLAY INVISIBLE (1800 3125);
FORCEPROP 2 LAST REUSE_ID 7
J 0
(1800 3125);
DISPLAY 1.361702 (1800 3125);
PAINT ORANGE (1800 3125);
DISPLAY INVISIBLE (1800 3125);
FORCEPROP 0 LAST SPOF TRUE
J 0
(1800 3100);
DISPLAY 1.021277 (1800 3100);
PAINT ORANGE (1800 3100);
DISPLAY INVISIBLE (1800 3100);
FORCEPROP 2 LAST BOM_COST P5V_STBY_VR
J 0
(1800 3100);
DISPLAY 1.021277 (1800 3100);
PAINT ORANGE (1800 3100);
DISPLAY INVISIBLE (1800 3100);
FORCEPROP 2 LAST SEC_TYPE 0402
J 0
(1800 3125);
DISPLAY 1.361702 (1800 3125);
PAINT ORANGE (1800 3125);
DISPLAY INVISIBLE (1800 3125);
FORCEADD GND..1
(1750 2625);
FORCEPROP 3 LASTPIN (1750 2675) SIG_NAME AGND_P5V_STBY\g
J 0
(1760 2685);
DISPLAY 0.659574 (1760 2685);
PAINT MONO (1760 2685);
DISPLAY INVISIBLE (1760 2685);
FORCEPROP 1 LAST HDL_POWER AGND_P5V_STBY
J 0
(1600 2575);
DISPLAY 0.617021 (1600 2575);
PAINT GREEN (1600 2575);
FORCEPROP 1 LAST BODY_TYPE PLUMBING
J 0
(1705 2582);
DISPLAY 0.340426 (1705 2582);
PAINT GREEN (1705 2582);
DISPLAY INVISIBLE (1705 2582);
FORCEPROP 2 LAST CDS_LIB mstr_symbols
J 0
(1750 2625);
PAINT MONO (1750 2625);
DISPLAY INVISIBLE (1750 2625);
FORCEPROP 1 LAST VOLTAGE 0
J 0
(1750 2625);
DISPLAY 1.340426 (1750 2625);
PAINT SKYBLUE (1750 2625);
DISPLAY INVISIBLE (1750 2625);
FORCEPROP 1 LAST PATH I52
J 0
(1825 2625);
DISPLAY 0.872340 (1825 2625);
PAINT AQUA (1825 2625);
DISPLAY INVISIBLE (1825 2625);
FORCEPROP 1 LAST SIZE 1B
J 0
(1825 2575);
DISPLAY 1.170213 (1825 2575);
PAINT AQUA (1825 2575);
DISPLAY INVISIBLE (1825 2575);
FORCEADD CAP..2
(200 2575);
FORCEPROP 1 LAST TOLERANCE 10%
J 2
(75 2450);
DISPLAY 0.617021 (75 2450);
PAINT SKYBLUE (75 2450);
FORCEPROP 1 LAST MATERIAL X7R
J 0
(325 2500);
DISPLAY 0.617021 (325 2500);
PAINT SKYBLUE (325 2500);
FORCEPROP 1 LAST VOLTAGE 50V
J 0
(250 2500);
DISPLAY 0.617021 (250 2500);
PAINT SKYBLUE (250 2500);
FORCEPROP 1 LAST PACK_TYPE 0402LF
J 1
(375 2450);
DISPLAY 0.617021 (375 2450);
PAINT SKYBLUE (375 2450);
FORCEPROP 1 LAST VALUE 270PF
J 2
(175 2500);
DISPLAY 0.617021 (175 2500);
PAINT SKYBLUE (175 2500);
FORCEPROP 1 LAST PART_NUMBER A36096-065
J 1
(175 2450);
DISPLAY 0.617021 (175 2450);
PAINT BLUE (175 2450);
FORCEPROP 1 LASTPIN (100 2575) $PN 1
J 0
(90 2590);
DISPLAY 0.617021 (90 2590);
PAINT WHITE (90 2590);
FORCEPROP 1 LAST LOCATION C8E16
J 1
(200 2675);
DISPLAY 0.617021 (200 2675);
PAINT AQUA (200 2675);
FORCEPROP 1 LASTPIN (300 2575) $PN 2
J 0
(285 2590);
DISPLAY 0.617021 (285 2590);
PAINT WHITE (285 2590);
FORCEPROP 2 LAST ROOM P5V_STBY_VR
J 0
(200 2725);
DISPLAY 1.021277 (200 2725);
PAINT ORANGE (200 2725);
DISPLAY INVISIBLE (200 2725);
FORCEPROP 1 LAST PATH I53
J 0
(200 2775);
DISPLAY 0.978723 (200 2775);
PAINT WHITE (200 2775);
DISPLAY INVISIBLE (200 2775);
FORCEPROP 2 LAST CDS_LOCATION C8E16
J 1
(200 2675);
DISPLAY 0.617021 (200 2675);
PAINT AQUA (200 2675);
DISPLAY INVISIBLE (200 2675);
FORCEPROP 2 LAST SEC 1
J 0
(200 2825);
DISPLAY 0.914894 (200 2825);
PAINT MONO (200 2825);
DISPLAY INVISIBLE (200 2825);
FORCEPROP 2 LAST BOM_COST P5V_STBY_VR
J 0
(200 2775);
DISPLAY 1.021277 (200 2775);
PAINT ORANGE (200 2775);
DISPLAY INVISIBLE (200 2775);
FORCEPROP 2 LAST REUSE_ID 4
J 0
(200 2825);
DISPLAY 1.361702 (200 2825);
PAINT ORANGE (200 2825);
DISPLAY INVISIBLE (200 2825);
FORCEPROP 2 LAST CDS_LIB mstr_discrete
J 0
(200 2575);
DISPLAY 1.340426 (200 2575);
PAINT ORANGE (200 2575);
DISPLAY INVISIBLE (200 2575);
FORCEPROP 2 LAST SEC_TYPE 0402LF
J 0
(200 2825);
DISPLAY 1.361702 (200 2825);
PAINT ORANGE (200 2825);
DISPLAY INVISIBLE (200 2825);
FORCEADD RES..1
(-200 2200);
FORCEPROP 1 LAST WATTAGE 1/16W
J 2
(-225 2025);
DISPLAY 0.617021 (-225 2025);
PAINT SKYBLUE (-225 2025);
FORCEPROP 1 LAST MATERIAL CHIP
J 0
(-200 2025);
DISPLAY 0.617021 (-200 2025);
PAINT SKYBLUE (-200 2025);
FORCEPROP 1 LASTPIN (-300 2200) $PN 1
J 0
(-288 2212);
DISPLAY 0.617021 (-288 2212);
PAINT WHITE (-288 2212);
FORCEPROP 1 LAST VALUE 24.9K
J 2
(-200 2125);
DISPLAY 0.617021 (-200 2125);
PAINT SKYBLUE (-200 2125);
FORCEPROP 1 LAST PART_NUMBER G21796-254
J 0
(-400 2075);
DISPLAY 0.617021 (-400 2075);
PAINT BLUE (-400 2075);
FORCEPROP 1 LASTPIN (-100 2200) $PN 2
J 0
(-138 2212);
DISPLAY 0.617021 (-138 2212);
PAINT WHITE (-138 2212);
FORCEPROP 1 LAST LOCATION R8E39
J 0
(-250 2250);
DISPLAY 0.617021 (-250 2250);
PAINT AQUA (-250 2250);
FORCEPROP 1 LAST PACK_TYPE 0402
J 0
(-150 2075);
DISPLAY 0.617021 (-150 2075);
PAINT SKYBLUE (-150 2075);
FORCEPROP 1 LAST TOLERANCE 1%
J 0
(-125 2125);
DISPLAY 0.617021 (-125 2125);
PAINT SKYBLUE (-125 2125);
FORCEPROP 2 LAST CDS_LOCATION R8E39
J 0
(-250 2250);
DISPLAY 0.617021 (-250 2250);
PAINT AQUA (-250 2250);
DISPLAY INVISIBLE (-250 2250);
FORCEPROP 2 LAST CDS_LIB mstr_discrete
J 0
(-200 2200);
DISPLAY 1.340426 (-200 2200);
PAINT ORANGE (-200 2200);
DISPLAY INVISIBLE (-200 2200);
FORCEPROP 2 LAST ROOM P5V_STBY_VR
J 0
(-250 2300);
DISPLAY 1.021277 (-250 2300);
PAINT ORANGE (-250 2300);
DISPLAY INVISIBLE (-250 2300);
FORCEPROP 2 LAST REUSE_ID 10
J 0
(-250 2400);
DISPLAY 1.361702 (-250 2400);
PAINT ORANGE (-250 2400);
DISPLAY INVISIBLE (-250 2400);
FORCEPROP 2 LAST SEC_TYPE 0402
J 0
(-250 2400);
DISPLAY 1.361702 (-250 2400);
PAINT ORANGE (-250 2400);
DISPLAY INVISIBLE (-250 2400);
FORCEPROP 2 LAST SEC 1
J 0
(-250 2400);
DISPLAY 0.914894 (-250 2400);
PAINT MONO (-250 2400);
DISPLAY INVISIBLE (-250 2400);
FORCEPROP 2 LAST BOM_COST P5V_STBY_VR
J 0
(-250 2350);
DISPLAY 1.021277 (-250 2350);
PAINT ORANGE (-250 2350);
DISPLAY INVISIBLE (-250 2350);
FORCEPROP 1 LAST PATH I54
J 0
(-250 2350);
DISPLAY 0.978723 (-250 2350);
PAINT WHITE (-250 2350);
DISPLAY INVISIBLE (-250 2350);
FORCEADD GND..1
(1925 1325);
FORCEPROP 3 LASTPIN (1925 1375) SIG_NAME AGND_P5V_STBY\g
J 0
(1935 1385);
DISPLAY 0.659574 (1935 1385);
PAINT MONO (1935 1385);
DISPLAY INVISIBLE (1935 1385);
FORCEPROP 1 LAST HDL_POWER AGND_P5V_STBY
J 0
(1725 1250);
DISPLAY 0.617021 (1725 1250);
PAINT GREEN (1725 1250);
FORCEPROP 1 LAST PATH I55
J 0
(2000 1325);
DISPLAY 0.872340 (2000 1325);
PAINT AQUA (2000 1325);
DISPLAY INVISIBLE (2000 1325);
FORCEPROP 1 LAST BODY_TYPE PLUMBING
J 0
(1880 1282);
DISPLAY 0.340426 (1880 1282);
PAINT GREEN (1880 1282);
DISPLAY INVISIBLE (1880 1282);
FORCEPROP 2 LAST CDS_LIB mstr_symbols
J 0
(1925 1325);
PAINT MONO (1925 1325);
DISPLAY INVISIBLE (1925 1325);
FORCEPROP 1 LAST SIZE 1B
J 0
(2000 1275);
DISPLAY 1.170213 (2000 1275);
PAINT AQUA (2000 1275);
DISPLAY INVISIBLE (2000 1275);
FORCEPROP 1 LAST VOLTAGE 0
J 0
(1925 1325);
DISPLAY 1.340426 (1925 1325);
PAINT SKYBLUE (1925 1325);
DISPLAY INVISIBLE (1925 1325);
FORCEADD CAP..2
(575 2200);
FORCEPROP 1 LAST PACK_TYPE 0402LF
J 1
(500 1975);
DISPLAY 0.617021 (500 1975);
PAINT SKYBLUE (500 1975);
FORCEPROP 1 LAST MATERIAL X7R
J 0
(575 2025);
DISPLAY 0.617021 (575 2025);
PAINT SKYBLUE (575 2025);
FORCEPROP 1 LAST TOLERANCE 10%
J 2
(500 2025);
DISPLAY 0.617021 (500 2025);
PAINT SKYBLUE (500 2025);
FORCEPROP 1 LASTPIN (475 2200) $PN 1
J 0
(465 2215);
DISPLAY 0.617021 (465 2215);
PAINT WHITE (465 2215);
FORCEPROP 1 LAST VALUE 2200PF
J 2
(575 2125);
DISPLAY 0.617021 (575 2125);
PAINT SKYBLUE (575 2125);
FORCEPROP 1 LAST PART_NUMBER A36096-075
J 1
(550 2075);
DISPLAY 0.617021 (550 2075);
PAINT BLUE (550 2075);
FORCEPROP 1 LAST VOLTAGE 50V
J 0
(625 2125);
DISPLAY 0.617021 (625 2125);
PAINT SKYBLUE (625 2125);
FORCEPROP 1 LASTPIN (675 2200) $PN 2
J 0
(660 2215);
DISPLAY 0.617021 (660 2215);
PAINT WHITE (660 2215);
FORCEPROP 1 LAST LOCATION C8F1
J 1
(575 2300);
DISPLAY 0.617021 (575 2300);
PAINT AQUA (575 2300);
FORCEPROP 2 LAST CDS_LIB mstr_discrete
J 0
(575 2200);
DISPLAY 1.340426 (575 2200);
PAINT ORANGE (575 2200);
DISPLAY INVISIBLE (575 2200);
FORCEPROP 2 LAST CDS_LOCATION C8F1
J 1
(575 2300);
DISPLAY 0.617021 (575 2300);
PAINT AQUA (575 2300);
DISPLAY INVISIBLE (575 2300);
FORCEPROP 2 LAST SEC_TYPE 0402LF
J 0
(575 2450);
DISPLAY 1.361702 (575 2450);
PAINT ORANGE (575 2450);
DISPLAY INVISIBLE (575 2450);
FORCEPROP 2 LAST REUSE_ID 5
J 0
(575 2450);
DISPLAY 1.361702 (575 2450);
PAINT ORANGE (575 2450);
DISPLAY INVISIBLE (575 2450);
FORCEPROP 2 LAST BOM_COST P5V_STBY_VR
J 0
(575 2400);
DISPLAY 1.021277 (575 2400);
PAINT ORANGE (575 2400);
DISPLAY INVISIBLE (575 2400);
FORCEPROP 2 LAST SEC 1
J 0
(575 2450);
DISPLAY 0.914894 (575 2450);
PAINT MONO (575 2450);
DISPLAY INVISIBLE (575 2450);
FORCEPROP 1 LAST PATH I57
J 0
(575 2400);
DISPLAY 0.978723 (575 2400);
PAINT WHITE (575 2400);
DISPLAY INVISIBLE (575 2400);
FORCEPROP 2 LAST ROOM P5V_STBY_VR
J 0
(575 2350);
DISPLAY 1.021277 (575 2350);
PAINT ORANGE (575 2350);
DISPLAY INVISIBLE (575 2350);
FORCEADD RES..1
(1575 1550);
FORCEPROP 1 LASTPIN (1475 1550) $PN 1
J 0
(1487 1562);
DISPLAY 0.617021 (1487 1562);
PAINT WHITE (1487 1562);
FORCEPROP 1 LAST WATTAGE 1/16W
J 2
(1675 1400);
DISPLAY 0.617021 (1675 1400);
PAINT SKYBLUE (1675 1400);
FORCEPROP 1 LAST VALUE 0.0
J 2
(1550 1450);
DISPLAY 0.617021 (1550 1450);
PAINT SKYBLUE (1550 1450);
FORCEPROP 1 LAST PART_NUMBER G21497-005
J 0
(1525 1650);
DISPLAY 0.617021 (1525 1650);
PAINT BLUE (1525 1650);
FORCEPROP 1 LAST LOCATION R7E13
J 0
(1525 1600);
DISPLAY 0.617021 (1525 1600);
PAINT AQUA (1525 1600);
FORCEPROP 1 LAST MATERIAL CHIP
J 0
(1725 1400);
DISPLAY 0.617021 (1725 1400);
PAINT SKYBLUE (1725 1400);
FORCEPROP 1 LAST PACK_TYPE 0402
J 0
(1750 1450);
DISPLAY 0.617021 (1750 1450);
PAINT SKYBLUE (1750 1450);
FORCEPROP 1 LAST TOLERANCE 5%
J 0
(1575 1450);
DISPLAY 0.617021 (1575 1450);
PAINT SKYBLUE (1575 1450);
FORCEPROP 1 LASTPIN (1675 1550) $PN 2
J 0
(1637 1562);
DISPLAY 0.617021 (1637 1562);
PAINT WHITE (1637 1562);
FORCEPROP 2 LAST ROOM P5V_STBY_VR
J 0
(1525 1700);
DISPLAY 1.021277 (1525 1700);
PAINT ORANGE (1525 1700);
DISPLAY INVISIBLE (1525 1700);
FORCEPROP 1 LAST PATH I58
J 0
(1525 1700);
DISPLAY 0.978723 (1525 1700);
PAINT WHITE (1525 1700);
DISPLAY INVISIBLE (1525 1700);
FORCEPROP 2 LAST CDS_LOCATION R7E13
J 0
(1525 1600);
DISPLAY 0.617021 (1525 1600);
PAINT AQUA (1525 1600);
DISPLAY INVISIBLE (1525 1600);
FORCEPROP 2 LAST SEC 1
J 0
(1525 1750);
DISPLAY 0.914894 (1525 1750);
PAINT MONO (1525 1750);
DISPLAY INVISIBLE (1525 1750);
FORCEPROP 2 LAST BOM_COST P5V_STBY_VR
J 0
(1525 1750);
DISPLAY 1.021277 (1525 1750);
PAINT ORANGE (1525 1750);
DISPLAY INVISIBLE (1525 1750);
FORCEPROP 2 LAST SEC_TYPE 0402
J 0
(1525 1750);
DISPLAY 1.021277 (1525 1750);
PAINT ORANGE (1525 1750);
DISPLAY INVISIBLE (1525 1750);
FORCEPROP 2 LAST $REUSE_ID 13
J 0
(1625 1775);
DISPLAY 1.361702 (1625 1775);
PAINT ORANGE (1625 1775);
DISPLAY INVISIBLE (1625 1775);
FORCEPROP 2 LAST SPOF TRUE
J 0
(1620 1730);
DISPLAY 1.340426 (1620 1730);
PAINT MONO (1620 1730);
DISPLAY INVISIBLE (1620 1730);
FORCEPROP 2 LAST CDS_LIB mstr_discrete
J 0
(1575 1550);
PAINT MONO (1575 1550);
DISPLAY INVISIBLE (1575 1550);
FORCEADD GND..1
(1350 1325);
FORCEPROP 3 LASTPIN (1350 1375) SIG_NAME GND\g
J 0
(1360 1385);
DISPLAY 0.659574 (1360 1385);
PAINT MONO (1360 1385);
DISPLAY INVISIBLE (1360 1385);
FORCEPROP 1 LAST VOLTAGE 0
J 0
(1350 1325);
DISPLAY 1.340426 (1350 1325);
PAINT SKYBLUE (1350 1325);
DISPLAY INVISIBLE (1350 1325);
FORCEPROP 2 LAST CDS_LIB mstr_symbols
J 0
(1350 1325);
DISPLAY 1.340426 (1350 1325);
PAINT MONO (1350 1325);
DISPLAY INVISIBLE (1350 1325);
FORCEPROP 1 LAST SIZE 1B
J 0
(1425 1275);
DISPLAY 1.170213 (1425 1275);
PAINT AQUA (1425 1275);
DISPLAY INVISIBLE (1425 1275);
FORCEPROP 1 LAST BODY_TYPE PLUMBING
J 0
(1305 1282);
DISPLAY 0.340426 (1305 1282);
PAINT GREEN (1305 1282);
DISPLAY INVISIBLE (1305 1282);
FORCEPROP 1 LAST PATH I59
J 0
(1425 1325);
DISPLAY 0.872340 (1425 1325);
PAINT AQUA (1425 1325);
DISPLAY INVISIBLE (1425 1325);
FORCEPROP 1 LAST HDL_POWER GND
J 0
(1350 1475);
DISPLAY 1.170213 (1350 1475);
PAINT GREEN (1350 1475);
DISPLAY INVISIBLE (1350 1475);
FORCEADD CAP..1
R 2
(-1025 3000);
FORCEPROP 1 LASTPIN (-1025 2900) $PN 2
J 2
(-1035 2880);
DISPLAY 0.617021 (-1035 2880);
PAINT WHITE (-1035 2880);
FORCEPROP 1 LAST MATERIAL X7R
J 2
(-1075 2900);
DISPLAY 0.617021 (-1075 2900);
PAINT SKYBLUE (-1075 2900);
FORCEPROP 1 LAST VOLTAGE 16V
J 2
(-1075 3000);
DISPLAY 0.617021 (-1075 3000);
PAINT SKYBLUE (-1075 3000);
FORCEPROP 1 LAST PACK_TYPE 0402LF
J 2
(-1075 2825);
DISPLAY 0.617021 (-1075 2825);
PAINT SKYBLUE (-1075 2825);
FORCEPROP 1 LAST TOLERANCE 10%
J 2
(-1075 2950);
DISPLAY 0.617021 (-1075 2950);
PAINT SKYBLUE (-1075 2950);
FORCEPROP 1 LAST VALUE 0.022UF
J 2
(-1075 3050);
DISPLAY 0.617021 (-1075 3050);
PAINT SKYBLUE (-1075 3050);
FORCEPROP 1 LAST LOCATION C8E15
J 2
(-1075 3100);
DISPLAY 0.617021 (-1075 3100);
PAINT AQUA (-1075 3100);
FORCEPROP 1 LASTPIN (-1025 3100) $PN 1
J 2
(-1035 3080);
DISPLAY 0.617021 (-1035 3080);
PAINT WHITE (-1035 3080);
FORCEPROP 1 LAST PART_NUMBER A36096-073
R 1
J 2
(-950 3175);
DISPLAY 0.617021 (-950 3175);
PAINT BLUE (-950 3175);
FORCEPROP 2 LAST CDS_LIB mstr_discrete
J 0
(-1025 3000);
DISPLAY 1.340426 (-1025 3000);
PAINT ORANGE (-1025 3000);
DISPLAY INVISIBLE (-1025 3000);
FORCEPROP 2 LAST SEC_TYPE 0402LF
J 0
(-1075 3200);
DISPLAY 1.361702 (-1075 3200);
PAINT ORANGE (-1075 3200);
DISPLAY INVISIBLE (-1075 3200);
FORCEPROP 2 LAST REUSE_ID 16
J 0
(-1075 3200);
DISPLAY 1.361702 (-1075 3200);
PAINT ORANGE (-1075 3200);
DISPLAY INVISIBLE (-1075 3200);
FORCEPROP 2 LAST BOM_COST P5V_STBY_VR
J 0
(-1075 3200);
DISPLAY 1.021277 (-1075 3200);
PAINT ORANGE (-1075 3200);
DISPLAY INVISIBLE (-1075 3200);
FORCEPROP 2 LAST SEC 1
J 0
(-1075 3200);
DISPLAY 0.914894 (-1075 3200);
PAINT MONO (-1075 3200);
DISPLAY INVISIBLE (-1075 3200);
FORCEPROP 2 LAST CDS_LOCATION C8E15
J 2
(-1075 3100);
DISPLAY 0.617021 (-1075 3100);
PAINT AQUA (-1075 3100);
DISPLAY INVISIBLE (-1075 3100);
FORCEPROP 1 LAST PATH I63
J 2
(-1075 3150);
DISPLAY 0.978723 (-1075 3150);
PAINT WHITE (-1075 3150);
DISPLAY INVISIBLE (-1075 3150);
FORCEPROP 2 LAST ROOM P5V_STBY_VR
J 0
(-1075 3150);
DISPLAY 1.021277 (-1075 3150);
PAINT ORANGE (-1075 3150);
DISPLAY INVISIBLE (-1075 3150);
FORCEADD GND..1
(-925 2200);
FORCEPROP 3 LASTPIN (-925 2250) SIG_NAME AGND_P5V_STBY\g
J 0
(-915 2260);
DISPLAY 0.659574 (-915 2260);
PAINT MONO (-915 2260);
DISPLAY INVISIBLE (-915 2260);
FORCEPROP 1 LAST HDL_POWER AGND_P5V_STBY
J 0
(-1100 2150);
DISPLAY 0.617021 (-1100 2150);
PAINT GREEN (-1100 2150);
FORCEPROP 1 LAST PATH I64
J 0
(-850 2200);
DISPLAY 0.872340 (-850 2200);
PAINT AQUA (-850 2200);
DISPLAY INVISIBLE (-850 2200);
FORCEPROP 1 LAST BODY_TYPE PLUMBING
J 0
(-970 2157);
DISPLAY 0.340426 (-970 2157);
PAINT GREEN (-970 2157);
DISPLAY INVISIBLE (-970 2157);
FORCEPROP 1 LAST SIZE 1B
J 0
(-850 2150);
DISPLAY 1.170213 (-850 2150);
PAINT AQUA (-850 2150);
DISPLAY INVISIBLE (-850 2150);
FORCEPROP 2 LAST CDS_LIB mstr_symbols
J 0
(-925 2200);
PAINT MONO (-925 2200);
DISPLAY INVISIBLE (-925 2200);
FORCEPROP 1 LAST VOLTAGE 0
J 0
(-925 2200);
DISPLAY 1.340426 (-925 2200);
PAINT SKYBLUE (-925 2200);
DISPLAY INVISIBLE (-925 2200);
FORCEADD P5V_STBY..1
(3175 4325);
FORCEPROP 3 LASTPIN (3175 4275) SIG_NAME P5V_STBY\g
J 0
(3185 4285);
DISPLAY 0.659574 (3185 4285);
PAINT MONO (3185 4285);
DISPLAY INVISIBLE (3185 4285);
FORCEPROP 1 LAST HDL_POWER P5V_STBY
J 0
(2875 4200);
DISPLAY 0.872340 (2875 4200);
PAINT ORANGE (2875 4200);
DISPLAY INVISIBLE (2875 4200);
FORCEPROP 1 LAST PATH I69
J 0
(3220 4327);
DISPLAY 0.340426 (3220 4327);
PAINT GREEN (3220 4327);
DISPLAY INVISIBLE (3220 4327);
FORCEPROP 1 LAST BODY_TYPE PLUMBING
J 0
(3130 4282);
DISPLAY 0.340426 (3130 4282);
PAINT GREEN (3130 4282);
DISPLAY INVISIBLE (3130 4282);
FORCEPROP 1 LAST VOLTAGE +5
J 0
(3375 4475);
DISPLAY 1.021277 (3375 4475);
PAINT SKYBLUE (3375 4475);
DISPLAY INVISIBLE (3375 4475);
FORCEPROP 2 LAST CDS_LIB mstr_symbols
J 0
(3175 4325);
PAINT ORANGE (3175 4325);
DISPLAY INVISIBLE (3175 4325);
FORCEPROP 1 LAST SIZE 1B
J 0
(3220 4347);
DISPLAY 0.340426 (3220 4347);
PAINT GREEN (3220 4347);
DISPLAY INVISIBLE (3220 4347);
FORCEADD P12V_STBY..1
(-3525 4875);
FORCEPROP 3 LASTPIN (-3525 4825) SIG_NAME P12V_STBY\g
J 0
(-3515 4835);
DISPLAY 0.659574 (-3515 4835);
PAINT MONO (-3515 4835);
DISPLAY INVISIBLE (-3515 4835);
FORCEPROP 1 LAST HDL_POWER P12V_STBY
J 0
(-3825 4750);
DISPLAY 0.872340 (-3825 4750);
PAINT ORANGE (-3825 4750);
DISPLAY INVISIBLE (-3825 4750);
FORCEPROP 1 LAST VOLTAGE 12.0V
J 0
(-3570 4832);
DISPLAY 0.340426 (-3570 4832);
PAINT SKYBLUE (-3570 4832);
DISPLAY INVISIBLE (-3570 4832);
FORCEPROP 1 LAST BODY_TYPE PLUMBING
J 0
(-3570 4832);
DISPLAY 0.340426 (-3570 4832);
PAINT GREEN (-3570 4832);
DISPLAY INVISIBLE (-3570 4832);
FORCEPROP 1 LAST SIZE 1B
J 0
(-3480 4897);
DISPLAY 0.340426 (-3480 4897);
PAINT GREEN (-3480 4897);
DISPLAY INVISIBLE (-3480 4897);
FORCEPROP 2 LAST CDS_LIB mstr_symbols
J 0
(-3525 4875);
PAINT ORANGE (-3525 4875);
DISPLAY INVISIBLE (-3525 4875);
FORCEPROP 1 LAST PATH I71
J 0
(-3480 4877);
DISPLAY 0.340426 (-3480 4877);
PAINT GREEN (-3480 4877);
DISPLAY INVISIBLE (-3480 4877);
FORCEADD RES..1
(2075 3650);
FORCEPROP 1 LASTPIN (1975 3650) $PN 1
J 0
(1987 3662);
DISPLAY 0.617021 (1987 3662);
PAINT ORANGE (1987 3662);
FORCEPROP 1 LAST VALUE 0.0
J 2
(1950 3700);
DISPLAY 0.617021 (1950 3700);
PAINT SKYBLUE (1950 3700);
FORCEPROP 1 LAST LOCATION R8E37
J 0
(1875 3825);
DISPLAY 0.617021 (1875 3825);
PAINT AQUA (1875 3825);
FORCEPROP 0 LAST SPOF TRUE
J 0
(1875 3925);
DISPLAY 1.021277 (1875 3925);
PAINT ORANGE (1875 3925);
FORCEPROP 1 LAST WATTAGE 1/16W
J 2
(2150 3575);
DISPLAY 0.617021 (2150 3575);
PAINT SKYBLUE (2150 3575);
FORCEPROP 1 LAST PACK_TYPE 0402
J 0
(2025 3550);
DISPLAY 0.617021 (2025 3550);
PAINT SKYBLUE (2025 3550);
FORCEPROP 1 LAST TOLERANCE 5%
J 0
(2025 3700);
DISPLAY 0.617021 (2025 3700);
PAINT SKYBLUE (2025 3700);
FORCEPROP 1 LAST PART_NUMBER G21497-005
J 0
(1900 3775);
DISPLAY 0.617021 (1900 3775);
PAINT BLUE (1900 3775);
FORCEPROP 1 LASTPIN (2175 3650) $PN 2
J 0
(2137 3662);
DISPLAY 0.617021 (2137 3662);
PAINT ORANGE (2137 3662);
FORCEPROP 1 LAST PATH I78
J 0
(2025 3800);
DISPLAY 0.978723 (2025 3800);
PAINT WHITE (2025 3800);
DISPLAY INVISIBLE (2025 3800);
FORCEPROP 2 LAST CDS_LOCATION R8E37
J 0
(1875 3825);
DISPLAY 0.617021 (1875 3825);
PAINT AQUA (1875 3825);
DISPLAY INVISIBLE (1875 3825);
FORCEPROP 2 LAST ROOM P5V_STBY_VR
J 0
(1875 3875);
DISPLAY 1.021277 (1875 3875);
PAINT ORANGE (1875 3875);
DISPLAY INVISIBLE (1875 3875);
FORCEPROP 2 LAST SEC 1
J 0
(2045 3870);
DISPLAY 0.680851 (2045 3870);
PAINT MONO (2045 3870);
DISPLAY INVISIBLE (2045 3870);
FORCEPROP 2 LAST BOM_COST P5V_STBY_VR
J 0
(1875 3925);
DISPLAY 1.021277 (1875 3925);
PAINT ORANGE (1875 3925);
DISPLAY INVISIBLE (1875 3925);
FORCEPROP 2 LAST SEC_TYPE 0402
J 0
(2045 3870);
DISPLAY 1.021277 (2045 3870);
PAINT ORANGE (2045 3870);
DISPLAY INVISIBLE (2045 3870);
FORCEPROP 1 LAST MATERIAL CHIP
J 0
(2075 3500);
PAINT SKYBLUE (2075 3500);
DISPLAY INVISIBLE (2075 3500);
FORCEPROP 2 LAST CDS_LIB mstr_discrete
J 0
(2075 3650);
PAINT ORANGE (2075 3650);
DISPLAY INVISIBLE (2075 3650);
FORCEADD CAPP..3
R 6
(2950 3875);
FORCEPROP 1 LASTPIN (2950 3775) $PN 2
J 0
(2955 3760);
DISPLAY 0.617021 (2955 3760);
PAINT WHITE (2955 3760);
FORCEPROP 1 LAST PART_NUMBER 724613-091
R 1
J 2
(2900 4040);
DISPLAY 0.617021 (2900 4040);
PAINT BLUE (2900 4040);
FORCEPROP 1 LASTPIN (2950 3975) $PN 1
J 0
(2955 3950);
DISPLAY 0.617021 (2955 3950);
PAINT WHITE (2955 3950);
FORCEPROP 1 LAST MATERIAL POSCAP
J 0
(3000 3940);
DISPLAY 0.617021 (3000 3940);
PAINT SKYBLUE (3000 3940);
FORCEPROP 1 LAST VOLTAGE 6.3V
J 0
(3000 3890);
DISPLAY 0.617021 (3000 3890);
PAINT SKYBLUE (3000 3890);
FORCEPROP 1 LAST PACK_TYPE 3018
J 0
(3000 3990);
DISPLAY 0.617021 (3000 3990);
PAINT SKYBLUE (3000 3990);
FORCEPROP 1 LAST TOLERANCE 20%
J 0
(3000 3840);
DISPLAY 0.617021 (3000 3840);
PAINT SKYBLUE (3000 3840);
FORCEPROP 1 LAST VALUE 470UF
J 0
(3000 3790);
DISPLAY 0.617021 (3000 3790);
PAINT SKYBLUE (3000 3790);
FORCEPROP 1 LAST LOCATION C8E4
J 0
(3000 3740);
DISPLAY 0.617021 (3000 3740);
PAINT AQUA (3000 3740);
FORCEPROP 1 LAST PATH I8
J 0
(3000 3725);
DISPLAY 0.978723 (3000 3725);
PAINT ORANGE (3000 3725);
DISPLAY INVISIBLE (3000 3725);
FORCEPROP 2 LAST CDS_LOCATION C8E4
J 0
(3000 3740);
DISPLAY 0.617021 (3000 3740);
PAINT AQUA (3000 3740);
DISPLAY INVISIBLE (3000 3740);
FORCEPROP 2 LAST SEC 1
J 0
(3000 3643);
DISPLAY 0.914894 (3000 3643);
PAINT MONO (3000 3643);
DISPLAY INVISIBLE (3000 3643);
FORCEPROP 2 LAST REUSE_ID 28
J 0
(3000 3627);
DISPLAY 1.361702 (3000 3627);
PAINT ORANGE (3000 3627);
DISPLAY INVISIBLE (3000 3627);
FORCEPROP 2 LAST SEC_TYPE 3018
J 0
(3000 3627);
DISPLAY 1.361702 (3000 3627);
PAINT ORANGE (3000 3627);
DISPLAY INVISIBLE (3000 3627);
FORCEPROP 2 LAST CDS_LIB mstr_discrete
J 0
(2950 3828);
DISPLAY 1.340426 (2950 3828);
PAINT ORANGE (2950 3828);
DISPLAY INVISIBLE (2950 3828);
FORCEADD FERRITE..1
(-3300 4675);
FORCEPROP 1 LAST VALUE 22
J 2
(-3420 4575);
DISPLAY 0.617021 (-3420 4575);
PAINT SKYBLUE (-3420 4575);
FORCEPROP 1 LAST MATERIAL FB
J 0
(-3395 4575);
DISPLAY 0.617021 (-3395 4575);
PAINT SKYBLUE (-3395 4575);
FORCEPROP 1 LAST PACK_TYPE SM
J 0
(-3320 4575);
DISPLAY 0.617021 (-3320 4575);
PAINT SKYBLUE (-3320 4575);
FORCEPROP 1 LAST PART_NUMBER 656554-051
J 0
(-3470 4615);
DISPLAY 0.617021 (-3470 4615);
PAINT BLUE (-3470 4615);
FORCEPROP 1 LAST LOCATION FB7E1
J 0
(-3395 4730);
DISPLAY 0.617021 (-3395 4730);
PAINT AQUA (-3395 4730);
FORCEPROP 2 LAST CDS_LOCATION FB7E1
J 0
(-3395 4730);
DISPLAY 0.617021 (-3395 4730);
PAINT AQUA (-3395 4730);
DISPLAY INVISIBLE (-3395 4730);
FORCEPROP 2 LAST ROOM P5V_STBY_VR
J 0
(-3375 4775);
DISPLAY 1.021277 (-3375 4775);
PAINT ORANGE (-3375 4775);
DISPLAY INVISIBLE (-3375 4775);
FORCEPROP 1 LASTPIN (-3400 4675) $PN 1
J 2
(-3365 4685);
DISPLAY 0.702128 (-3365 4685);
PAINT WHITE (-3365 4685);
DISPLAY INVISIBLE (-3365 4685);
FORCEPROP 2 LAST BOM_COST P5V_STBY_VR
J 0
(-3375 4825);
DISPLAY 1.021277 (-3375 4825);
PAINT ORANGE (-3375 4825);
DISPLAY INVISIBLE (-3375 4825);
FORCEPROP 1 LAST PATH I82
J 0
(-3395 4840);
DISPLAY 0.872340 (-3395 4840);
PAINT PURPLE (-3395 4840);
DISPLAY INVISIBLE (-3395 4840);
FORCEPROP 2 LAST CDS_SEC 1
J 0
(-3375 4900);
PAINT MONO (-3375 4900);
DISPLAY INVISIBLE (-3375 4900);
FORCEPROP 2 LAST $SEC 1
J 0
(-3375 4900);
PAINT MONO (-3375 4900);
DISPLAY INVISIBLE (-3375 4900);
FORCEPROP 1 LASTPIN (-3200 4675) $PN 2
J 0
(-3220 4685);
DISPLAY 0.702128 (-3220 4685);
PAINT WHITE (-3220 4685);
DISPLAY INVISIBLE (-3220 4685);
FORCEPROP 2 LAST CDS_LIB mstr_discrete
J 0
(-3300 4675);
PAINT ORANGE (-3300 4675);
DISPLAY INVISIBLE (-3300 4675);
FORCEADD TPS54821..1
(125 3575);
FORCEPROP 2 LASTPIN (-275 3275) $PN 8
J 2
(-285 3285);
DISPLAY 0.617021 (-285 3285);
PAINT ORANGE (-285 3285);
FORCEPROP 2 LASTPIN (-275 3475) $PN 10
J 2
(-285 3485);
DISPLAY 0.617021 (-285 3485);
PAINT ORANGE (-285 3485);
FORCEPROP 2 LASTPIN (-275 3325) $PN 1
J 2
(-285 3335);
DISPLAY 0.617021 (-285 3335);
PAINT ORANGE (-285 3335);
FORCEPROP 2 LASTPIN (-275 3375) $PN 9
J 2
(-285 3385);
DISPLAY 0.617021 (-285 3385);
PAINT ORANGE (-285 3385);
FORCEPROP 2 LASTPIN (-275 3575) $PN 6
J 2
(-285 3585);
DISPLAY 0.617021 (-285 3585);
PAINT ORANGE (-285 3585);
FORCEPROP 2 LASTPIN (-275 3775) $PN 5
J 2
(-285 3785);
DISPLAY 0.617021 (-285 3785);
PAINT ORANGE (-285 3785);
FORCEPROP 2 LASTPIN (-275 3725) $PN 4
J 2
(-285 3735);
DISPLAY 0.617021 (-285 3735);
PAINT ORANGE (-285 3735);
FORCEPROP 1 LAST LOCATION EU7E2
J 0
(-225 4025);
DISPLAY 0.617021 (-225 4025);
PAINT AQUA (-225 4025);
FORCEPROP 1 LAST MATERIAL IC
J 0
(-225 3975);
DISPLAY 0.617021 (-225 3975);
PAINT SKYBLUE (-225 3975);
FORCEPROP 1 LAST PART_NUMBER H63269-001
J 0
(-225 3075);
DISPLAY 0.617021 (-225 3075);
PAINT BLUE (-225 3075);
FORCEPROP 2 LASTPIN (525 3225) $PN 15
J 0
(535 3235);
DISPLAY 0.617021 (535 3235);
PAINT ORANGE (535 3235);
FORCEPROP 2 LASTPIN (525 3275) $PN 2
J 0
(535 3285);
DISPLAY 0.617021 (535 3285);
PAINT ORANGE (535 3285);
FORCEPROP 2 LASTPIN (525 3325) $PN 3
J 0
(535 3335);
DISPLAY 0.617021 (535 3335);
PAINT ORANGE (535 3335);
FORCEPROP 2 LASTPIN (525 3525) $PN 11
J 0
(535 3535);
DISPLAY 0.617021 (535 3535);
PAINT ORANGE (535 3535);
FORCEPROP 2 LASTPIN (525 3425) $PN 7
J 0
(535 3435);
DISPLAY 0.617021 (535 3435);
PAINT ORANGE (535 3435);
FORCEPROP 2 LASTPIN (525 3775) $PN 14
J 0
(535 3785);
DISPLAY 0.617021 (535 3785);
PAINT ORANGE (535 3785);
FORCEPROP 2 LASTPIN (525 3575) $PN 12
J 0
(535 3585);
DISPLAY 0.617021 (535 3585);
PAINT ORANGE (535 3585);
FORCEPROP 2 LASTPIN (525 3675) $PN 13
J 0
(535 3685);
DISPLAY 0.617021 (535 3685);
PAINT ORANGE (535 3685);
FORCEPROP 2 LAST CDS_LOCATION EU7E2
J 0
(-225 4025);
DISPLAY 0.617021 (-225 4025);
PAINT AQUA (-225 4025);
DISPLAY INVISIBLE (-225 4025);
FORCEPROP 2 LAST ROOM P5V_STBY_VR
J 0
(-225 4075);
DISPLAY 1.021277 (-225 4075);
PAINT ORANGE (-225 4075);
DISPLAY INVISIBLE (-225 4075);
FORCEPROP 2 LAST SEC 1
J 0
(-225 4075);
DISPLAY 0.680851 (-225 4075);
PAINT MONO (-225 4075);
DISPLAY INVISIBLE (-225 4075);
FORCEPROP 2 LAST SEC_TYPE LCC
J 0
(-225 4075);
DISPLAY 1.021277 (-225 4075);
PAINT ORANGE (-225 4075);
DISPLAY INVISIBLE (-225 4075);
FORCEPROP 1 LAST PACK_TYPE LCC
J 0
(-225 4075);
PAINT SKYBLUE (-225 4075);
DISPLAY INVISIBLE (-225 4075);
FORCEPROP 2 LAST BOM_COST P5V_STBY_VR
J 0
(-225 4125);
DISPLAY 1.021277 (-225 4125);
PAINT ORANGE (-225 4125);
DISPLAY INVISIBLE (-225 4125);
FORCEPROP 1 LAST PATH I83
J 0
(175 3975);
PAINT GREEN (175 3975);
DISPLAY INVISIBLE (175 3975);
FORCEPROP 2 LAST CDS_LIB mstr_vreg
J 0
(125 3575);
PAINT ORANGE (125 3575);
DISPLAY INVISIBLE (125 3575);
FORCEADD P5V_STBY..1
(1225 5050);
FORCEPROP 3 LASTPIN (1225 5000) SIG_NAME P5V_STBY\g
J 0
(1235 5010);
DISPLAY 0.659574 (1235 5010);
PAINT MONO (1235 5010);
DISPLAY INVISIBLE (1235 5010);
FORCEPROP 1 LAST HDL_POWER P5V_STBY
J 0
(925 4925);
DISPLAY 0.872340 (925 4925);
PAINT ORANGE (925 4925);
DISPLAY INVISIBLE (925 4925);
FORCEPROP 1 LAST PATH I85
J 0
(1270 5052);
DISPLAY 0.340426 (1270 5052);
PAINT GREEN (1270 5052);
DISPLAY INVISIBLE (1270 5052);
FORCEPROP 1 LAST BODY_TYPE PLUMBING
J 0
(1180 5007);
DISPLAY 0.340426 (1180 5007);
PAINT GREEN (1180 5007);
DISPLAY INVISIBLE (1180 5007);
FORCEPROP 1 LAST SIZE 1B
J 0
(1270 5072);
DISPLAY 0.340426 (1270 5072);
PAINT GREEN (1270 5072);
DISPLAY INVISIBLE (1270 5072);
FORCEPROP 2 LAST CDS_LIB mstr_symbols
J 0
(1225 5050);
PAINT ORANGE (1225 5050);
DISPLAY INVISIBLE (1225 5050);
FORCEPROP 1 LAST VOLTAGE +5.0V
J 0
(1425 5200);
DISPLAY 1.021277 (1425 5200);
PAINT SKYBLUE (1425 5200);
DISPLAY INVISIBLE (1425 5200);
FORCEADD GND..1
(975 2075);
FORCEPROP 3 LASTPIN (975 2125) SIG_NAME AGND_P5V_STBY\g
J 0
(985 2135);
DISPLAY 0.659574 (985 2135);
PAINT MONO (985 2135);
DISPLAY INVISIBLE (985 2135);
FORCEPROP 1 LAST HDL_POWER AGND_P5V_STBY
J 0
(825 2025);
DISPLAY 0.617021 (825 2025);
PAINT GREEN (825 2025);
FORCEPROP 1 LAST BODY_TYPE PLUMBING
J 0
(930 2032);
DISPLAY 0.340426 (930 2032);
PAINT GREEN (930 2032);
DISPLAY INVISIBLE (930 2032);
FORCEPROP 1 LAST SIZE 1B
J 0
(1050 2025);
DISPLAY 1.170213 (1050 2025);
PAINT AQUA (1050 2025);
DISPLAY INVISIBLE (1050 2025);
FORCEPROP 1 LAST VOLTAGE 0
J 0
(975 2075);
DISPLAY 1.340426 (975 2075);
PAINT SKYBLUE (975 2075);
DISPLAY INVISIBLE (975 2075);
FORCEPROP 2 LAST CDS_LIB mstr_symbols
J 0
(975 2075);
PAINT ORANGE (975 2075);
DISPLAY INVISIBLE (975 2075);
FORCEPROP 1 LAST PATH I86
J 0
(1050 2075);
DISPLAY 0.872340 (1050 2075);
PAINT AQUA (1050 2075);
DISPLAY INVISIBLE (1050 2075);
FORCEADD RES..1
(2250 4625);
FORCEPROP 1 LAST WATTAGE 1/16W
J 2
(2225 4475);
DISPLAY 0.617021 (2225 4475);
PAINT SKYBLUE (2225 4475);
FORCEPROP 1 LAST MATERIAL CHIP
J 0
(2250 4475);
DISPLAY 0.617021 (2250 4475);
PAINT SKYBLUE (2250 4475);
FORCEPROP 1 LAST TOLERANCE 1.0%
J 0
(2250 4525);
DISPLAY 0.617021 (2250 4525);
PAINT SKYBLUE (2250 4525);
FORCEPROP 1 LAST VALUE 22.1
J 2
(2225 4525);
DISPLAY 0.617021 (2225 4525);
PAINT SKYBLUE (2225 4525);
FORCEPROP 1 LASTPIN (2150 4625) $PN 1
J 0
(2162 4637);
DISPLAY 0.617021 (2162 4637);
PAINT ORANGE (2162 4637);
FORCEPROP 1 LAST PART_NUMBER G21796-250
J 0
(2200 4725);
DISPLAY 0.617021 (2200 4725);
PAINT BLUE (2200 4725);
FORCEPROP 1 LAST LOCATION R7E15
J 0
(2200 4675);
DISPLAY 0.617021 (2200 4675);
PAINT AQUA (2200 4675);
FORCEPROP 1 LASTPIN (2350 4625) $PN 2
J 0
(2312 4637);
DISPLAY 0.617021 (2312 4637);
PAINT ORANGE (2312 4637);
FORCEPROP 1 LAST PACK_TYPE 0402
J 0
(2500 4475);
DISPLAY 0.617021 (2500 4475);
PAINT SKYBLUE (2500 4475);
FORCEPROP 2 LAST CDS_LOCATION R7E15
J 0
(2200 4675);
DISPLAY 0.617021 (2200 4675);
PAINT AQUA (2200 4675);
DISPLAY INVISIBLE (2200 4675);
FORCEPROP 2 LAST SEC 1
J 0
(2200 4825);
DISPLAY 0.680851 (2200 4825);
PAINT MONO (2200 4825);
DISPLAY INVISIBLE (2200 4825);
FORCEPROP 2 LAST CDS_LIB mstr_discrete
J 0
(2250 4625);
PAINT MONO (2250 4625);
DISPLAY INVISIBLE (2250 4625);
FORCEPROP 1 LAST PATH I89
J 0
(2200 4775);
DISPLAY 0.978723 (2200 4775);
PAINT WHITE (2200 4775);
DISPLAY INVISIBLE (2200 4775);
FORCEPROP 0 LAST ROOM P5V_STBY_VR
J 0
(2200 4825);
DISPLAY 1.021277 (2200 4825);
PAINT ORANGE (2200 4825);
DISPLAY INVISIBLE (2200 4825);
FORCEPROP 2 LAST SEC_TYPE 0402
J 0
(2200 4825);
DISPLAY 1.021277 (2200 4825);
PAINT ORANGE (2200 4825);
DISPLAY INVISIBLE (2200 4825);
FORCEADD RES..2
(2550 3875);
FORCEPROP 1 LAST PART_NUMBER G85996-004
R 1
J 0
(2515 3650);
DISPLAY 0.617021 (2515 3650);
PAINT BLUE (2515 3650);
FORCEPROP 1 LASTPIN (2550 3975) $PN 1
J 0
(2555 3937);
DISPLAY 0.617021 (2555 3937);
PAINT WHITE (2555 3937);
FORCEPROP 1 LASTPIN (2550 3775) $PN 2
J 0
(2555 3785);
DISPLAY 0.617021 (2555 3785);
PAINT WHITE (2555 3785);
FORCEPROP 1 LAST WATTAGE 1/16W
J 0
(2590 3800);
DISPLAY 0.617021 (2590 3800);
PAINT SKYBLUE (2590 3800);
FORCEPROP 1 LAST MATERIAL CHIP
J 0
(2590 3750);
DISPLAY 0.617021 (2590 3750);
PAINT SKYBLUE (2590 3750);
FORCEPROP 1 LAST PACK_TYPE 0402
J 0
(2590 3700);
DISPLAY 0.617021 (2590 3700);
PAINT SKYBLUE (2590 3700);
FORCEPROP 1 LAST TOLERANCE 0.1%
J 0
(2595 3850);
DISPLAY 0.617021 (2595 3850);
PAINT SKYBLUE (2595 3850);
FORCEPROP 1 LAST VALUE 1.0K
J 0
(2595 3900);
DISPLAY 0.617021 (2595 3900);
PAINT SKYBLUE (2595 3900);
FORCEPROP 1 LAST LOCATION R8E18
J 0
(2595 3950);
DISPLAY 0.617021 (2595 3950);
PAINT AQUA (2595 3950);
FORCEPROP 2 LAST CDS_LIB mstr_discrete
J 0
(2550 3875);
DISPLAY 1.340426 (2550 3875);
PAINT ORANGE (2550 3875);
DISPLAY INVISIBLE (2550 3875);
FORCEPROP 2 LAST ROOM P5V_STBY_VR
J 0
(2600 4000);
DISPLAY 1.021277 (2600 4000);
PAINT ORANGE (2600 4000);
DISPLAY INVISIBLE (2600 4000);
FORCEPROP 1 LAST PATH I9
J 0
(2600 4050);
DISPLAY 0.978723 (2600 4050);
PAINT WHITE (2600 4050);
DISPLAY INVISIBLE (2600 4050);
FORCEPROP 2 LAST CDS_LOCATION R8E18
J 0
(2595 3950);
DISPLAY 0.617021 (2595 3950);
PAINT AQUA (2595 3950);
DISPLAY INVISIBLE (2595 3950);
FORCEPROP 2 LAST BOM_COST P5V_STBY_VR
J 0
(2600 4050);
DISPLAY 1.021277 (2600 4050);
PAINT ORANGE (2600 4050);
DISPLAY INVISIBLE (2600 4050);
FORCEPROP 2 LAST SEC 1
J 0
(2600 4100);
DISPLAY 0.914894 (2600 4100);
PAINT MONO (2600 4100);
DISPLAY INVISIBLE (2600 4100);
FORCEPROP 2 LAST REUSE_ID 34
J 0
(2600 4100);
DISPLAY 1.361702 (2600 4100);
PAINT ORANGE (2600 4100);
DISPLAY INVISIBLE (2600 4100);
FORCEPROP 2 LAST SEC_TYPE 0402
J 0
(2600 4100);
DISPLAY 1.361702 (2600 4100);
PAINT ORANGE (2600 4100);
DISPLAY INVISIBLE (2600 4100);
FORCEADD INDUCTOR..1
(2150 4075);
FORCEPROP 1 LAST VALUE 2.2UH
J 2
(2145 3990);
DISPLAY 0.617021 (2145 3990);
PAINT SKYBLUE (2145 3990);
FORCEPROP 1 LAST MATERIAL IND
J 0
(2165 3990);
DISPLAY 0.617021 (2165 3990);
PAINT SKYBLUE (2165 3990);
FORCEPROP 1 LAST PACK_TYPE SM
J 0
(2440 3990);
DISPLAY 0.617021 (2440 3990);
PAINT SKYBLUE (2440 3990);
FORCEPROP 1 LASTPIN (2050 4075) $PN 1
J 0
(2050 4085);
DISPLAY 0.617021 (2050 4085);
PAINT WHITE (2050 4085);
FORCEPROP 1 LASTPIN (2250 4075) $PN 2
J 2
(2260 4085);
DISPLAY 0.617021 (2260 4085);
PAINT WHITE (2260 4085);
FORCEPROP 1 LAST PART_NUMBER E98761-003
J 0
(2050 4175);
DISPLAY 0.617021 (2050 4175);
PAINT BLUE (2050 4175);
FORCEPROP 1 LAST LOCATION L8E1
J 0
(2050 4125);
DISPLAY 0.617021 (2050 4125);
PAINT AQUA (2050 4125);
FORCEPROP 2 LAST CDS_LIB mstr_discrete
J 0
(2150 4075);
PAINT MONO (2150 4075);
DISPLAY INVISIBLE (2150 4075);
FORCEPROP 2 LAST CDS_LOCATION L8E1
J 0
(2050 4125);
DISPLAY 0.617021 (2050 4125);
PAINT AQUA (2050 4125);
DISPLAY INVISIBLE (2050 4125);
FORCEPROP 1 LAST PATH I90
J 0
(2050 4225);
DISPLAY 0.978723 (2050 4225);
PAINT ORANGE (2050 4225);
DISPLAY INVISIBLE (2050 4225);
FORCEPROP 2 LAST CDS_SEC 1
J 0
(2050 4275);
PAINT MONO (2050 4275);
DISPLAY INVISIBLE (2050 4275);
FORCEPROP 2 LAST $SEC 1
J 0
(2050 4275);
PAINT MONO (2050 4275);
DISPLAY INVISIBLE (2050 4275);
FORCEADD RES..1
(-1625 3475);
FORCEPROP 1 LAST WATTAGE 1/16W
J 2
(-1650 3325);
DISPLAY 0.617021 (-1650 3325);
PAINT SKYBLUE (-1650 3325);
FORCEPROP 1 LAST VALUE 0.0
J 2
(-1725 3375);
DISPLAY 0.617021 (-1725 3375);
PAINT SKYBLUE (-1725 3375);
FORCEPROP 1 LASTPIN (-1725 3475) $PN 1
J 0
(-1713 3487);
DISPLAY 0.617021 (-1713 3487);
PAINT ORANGE (-1713 3487);
FORCEPROP 1 LAST TOLERANCE 5%
J 0
(-1675 3375);
DISPLAY 0.617021 (-1675 3375);
PAINT SKYBLUE (-1675 3375);
FORCEPROP 1 LASTPIN (-1525 3475) $PN 2
J 0
(-1563 3487);
DISPLAY 0.617021 (-1563 3487);
PAINT ORANGE (-1563 3487);
FORCEPROP 1 LAST MATERIAL CHIP
J 0
(-1625 3325);
DISPLAY 0.617021 (-1625 3325);
PAINT SKYBLUE (-1625 3325);
FORCEPROP 1 LAST PACK_TYPE 0402
J 0
(-1550 3375);
DISPLAY 0.617021 (-1550 3375);
PAINT SKYBLUE (-1550 3375);
FORCEPROP 1 LAST PART_NUMBER G21497-005
J 0
(-1775 3425);
DISPLAY 0.617021 (-1775 3425);
PAINT BLUE (-1775 3425);
FORCEPROP 1 LAST LOCATION R8E33
J 0
(-1675 3525);
DISPLAY 0.617021 (-1675 3525);
PAINT AQUA (-1675 3525);
FORCEPROP 2 LAST CDS_LOCATION R8E33
J 0
(-1675 3525);
DISPLAY 0.617021 (-1675 3525);
PAINT AQUA (-1675 3525);
DISPLAY INVISIBLE (-1675 3525);
FORCEPROP 2 LAST CDS_LIB mstr_discrete
J 0
(-1625 3475);
PAINT ORANGE (-1625 3475);
DISPLAY INVISIBLE (-1625 3475);
FORCEPROP 2 LAST ROOM PVCCIN_CPU0_VR
J 0
(-1675 3575);
DISPLAY 1.361702 (-1675 3575);
PAINT ORANGE (-1675 3575);
DISPLAY INVISIBLE (-1675 3575);
FORCEPROP 1 LAST PATH I91
J 0
(-1675 3625);
DISPLAY 0.978723 (-1675 3625);
PAINT WHITE (-1675 3625);
DISPLAY INVISIBLE (-1675 3625);
FORCEPROP 2 LAST SEC 1
J 0
(-1675 3675);
PAINT MONO (-1675 3675);
DISPLAY INVISIBLE (-1675 3675);
FORCEPROP 2 LAST SEC_TYPE 0402
J 0
(-1675 3675);
DISPLAY 1.021277 (-1675 3675);
PAINT ORANGE (-1675 3675);
DISPLAY INVISIBLE (-1675 3675);
FORCEADD INTEL_CORP_BPAGE..1
(4250 200);
FORCEPROP 1 LAST CDS_CON_LAST_MODIFIED Tue Dec 01 11:52:31 2015
J 0
(2825 525);
PAINT ORANGE (2825 525);
DISPLAY INVISIBLE (2825 525);
FORCEPROP 1 LAST CUSTOM_TXT_CDS <CURRENT_DESIGN_SHEET> OF <TOTAL_DESIGN_SHEETS>
J 0
(3750 225);
PAINT GREEN (3750 225);
FORCEPROP 1 LAST CUSTOM_TXT_CDS <CON_LAST_MODIFIED>
J 0
(2325 550);
PAINT GREEN (2325 550);
FORCEPROP 2 LAST CUSTOM_TXT_CDS <XR_PAGE_TITLE>
J 0
(-3640 5450);
DISPLAY 0.638298 (-3640 5450);
PAINT PINK (-3640 5450);
DISPLAY INVISIBLE (-3640 5450);
FORCEPROP 1 LAST SCH_NUMBER H4694802
J 0
(2950 350);
DISPLAY 1.212766 (2950 350);
PAINT YELLOW (2950 350);
FORCEPROP 1 LAST SCH_DEPT BESD
J 1
(-200 300);
DISPLAY 1.212766 (-200 300);
PAINT YELLOW (-200 300);
FORCEPROP 1 LAST SCH_REV 2.420
J 0
(4000 350);
DISPLAY 0.978723 (4000 350);
PAINT YELLOW (4000 350);
FORCEPROP 1 LAST SCH_TITLE P5V STBY VR
J 0
(-3700 250);
DISPLAY 1.212766 (-3700 250);
PAINT ORANGE (-3700 250);
FORCEPROP 1 LAST SCH_ADDRESS2 P.O. BOX 58119
J 0
(275 275);
DISPLAY 0.617021 (275 275);
PAINT GREEN (275 275);
FORCEPROP 1 LAST SCH_ADDRESS1 2200 Mission College Blvd.
J 0
(275 325);
DISPLAY 0.617021 (275 325);
PAINT GREEN (275 325);
FORCEPROP 1 LAST SCH_ADDRESS3 Santa Clara, CA 95052-8119
J 0
(275 225);
DISPLAY 0.617021 (275 225);
PAINT GREEN (275 225);
FORCEPROP 2 LAST PAGE_BORDER TRUE
J 0
(-3640 5450);
DISPLAY 0.638298 (-3640 5450);
PAINT PINK (-3640 5450);
DISPLAY INVISIBLE (-3640 5450);
FORCEPROP 1 LAST COMMENT_BODY TRUE
J 0
(4262 212);
DISPLAY 0.468085 (4262 212);
PAINT GREEN (4262 212);
DISPLAY INVISIBLE (4262 212);
FORCEPROP 2 LAST CDS_LIB mstr_symbols
J 0
(4250 200);
PAINT MONO (4250 200);
DISPLAY INVISIBLE (4250 200);
FORCEPROP 2 LAST CDS_XR_PAGE_TITLE CR-241 : @BASEBOARD_FAB2_LIB.BASEBOARD_FAB2(SCH_1):PAGE241
J 0
(-3640 5450);
DISPLAY 0.638298 (-3640 5450);
PAINT PINK (-3640 5450);
DISPLAY INVISIBLE (-3640 5450);
FORCEADD CAD_NOTE..1
(-1400 4525);
FORCEPROP 0 LAST LINE2 AND CLOSE TO IC PINS
J 0
(-1550 4325);
PAINT WHITE (-1550 4325);
FORCEPROP 0 LAST LINE PLACE DECOUPLING SAME SIDE
J 0
(-1550 4400);
PAINT WHITE (-1550 4400);
FORCEPROP 2 LAST CDS_LIB mstr_symbols
J 0
(-1400 4525);
DISPLAY 1.340426 (-1400 4525);
PAINT MONO (-1400 4525);
DISPLAY INVISIBLE (-1400 4525);
FORCEPROP 1 LAST COMMENT_BODY TRUE
J 0
(-1375 4625);
DISPLAY 1.340426 (-1375 4625);
PAINT GREEN (-1375 4625);
DISPLAY INVISIBLE (-1375 4625);
FORCEADD DESIGN_NOTE..1
(2775 2875);
FORCEPROP 0 LAST L3 TDC = 3 A
J 0
(2625 2575);
PAINT WHITE (2625 2575);
FORCEPROP 0 LAST L4 IMAX = 6A
J 0
(2625 2500);
PAINT WHITE (2625 2500);
FORCEPROP 0 LAST L10 
J 0
(2625 2350);
PAINT WHITE (2625 2350);
FORCEPROP 0 LAST L8 
J 0
(2625 2050);
PAINT WHITE (2625 2050);
FORCEPROP 0 LAST L2 VOUT = 5.0 V
J 0
(2625 2650);
PAINT WHITE (2625 2650);
FORCEPROP 0 LAST L5 STEP RATE= TBDA/US
J 0
(2625 2275);
PAINT WHITE (2625 2275);
FORCEPROP 0 LAST L9 VIN=FSW=650KHZ
J 0
(2625 2200);
PAINT WHITE (2625 2200);
FORCEPROP 0 LAST L7 DC TOLERANCE = +- 2 %
J 0
(2625 2425);
PAINT WHITE (2625 2425);
FORCEPROP 0 LAST L1 P5V_STBY VR SPECIFICATION
J 0
(2575 2750);
PAINT WHITE (2575 2750);
FORCEPROP 0 LAST L6 AC TOLERANCE = +- 2.5 %
J 0
(2625 2350);
PAINT WHITE (2625 2350);
FORCEPROP 2 LAST CDS_LIB mstr_symbols
J 0
(2775 2875);
DISPLAY 1.340426 (2775 2875);
PAINT MONO (2775 2875);
DISPLAY INVISIBLE (2775 2875);
FORCEPROP 1 LAST COMMENT_BODY TRUE
J 0
(2800 2975);
DISPLAY 1.319149 (2800 2975);
PAINT ORANGE (2800 2975);
DISPLAY INVISIBLE (2800 2975);
FORCEADD DNS..2
(-1995 3070);
PAINT RED (-1995 3070);
FORCEPROP 1 LAST COMMENT_BODY TRUE
R 1
J 0
(-1920 2845);
DISPLAY 0.872340 (-1920 2845);
PAINT GREEN (-1920 2845);
DISPLAY INVISIBLE (-1920 2845);
FORCEPROP 2 LAST CDS_LIB mstr_misc
J 0
(-1995 3070);
PAINT ORANGE (-1995 3070);
DISPLAY INVISIBLE (-1995 3070);
WIRE 16 -1 (1500 4200)(1500 4300);
WIRE 16 -1 (675 3275)(675 3325);
WIRE 16 -1 (675 3275)(675 3225);
WIRE 16 -1 (675 3275)(525 3275);
WIRE 16 -1 (675 3325)(525 3325);
WIRE 16 -1 (525 3225)(675 3225);
WIRE 16 -1 (675 3175)(675 3225);
WIRE 16 -1 (-2150 3750)(-2150 3600);
WIRE 16 -1 (-2000 2750)(-2000 2975);
WIRE 16 -1 (2550 3775)(2550 3650);
WIRE 16 -1 (2550 3650)(2950 3650);
WIRE 16 -1 (2950 3775)(2950 3650);
WIRE 16 -1 (3325 3650)(2950 3650);
WIRE 16 -1 (3600 3650)(3325 3650);
WIRE 16 -1 (3325 3650)(3325 3800);
WIRE 16 -1 (3700 3650)(3600 3650);
WIRE 16 -1 (3600 3650)(3600 3525);
WIRE 16 -1 (3700 3775)(3700 3650);
WIRE 16 -1 (-2550 4075)(-2550 4150);
WIRE 16 -1 (-2875 4075)(-2875 4175);
WIRE 16 -1 (-3225 4075)(-3225 4175);
WIRE 16 -1 (1750 2800)(1750 2675);
WIRE 16 -1 (1925 1550)(1675 1550);
WIRE 16 -1 (1925 1550)(1925 1375);
WIRE 16 -1 (1475 1550)(1350 1550);
WIRE 16 -1 (1350 1375)(1350 1550);
WIRE 16 -1 (-825 2500)(-825 2350);
WIRE 16 -1 (-825 2350)(-925 2350);
WIRE 16 -1 (-925 2350)(-1025 2350);
WIRE 16 -1 (-925 2250)(-925 2350);
WIRE 16 -1 (-1025 2900)(-1025 2350);
WIRE 16 -1 (2175 3650)(2375 3650);
WIRE 16 -1 (2375 3650)(2375 4075);
WIRE 16 -1 (2250 4075)(2375 4075);
WIRE 16 -1 (2375 4075)(2550 4075);
WIRE 16 -1 (2550 3975)(2550 4075);
WIRE 16 -1 (2550 4075)(2950 4075);
WIRE 16 -1 (3175 4075)(2950 4075);
WIRE 16 -1 (2950 4075)(2950 3975);
WIRE 16 -1 (3325 4075)(3175 4075);
WIRE 16 -1 (3175 4275)(3175 4075);
WIRE 16 -1 (3700 4075)(3325 4075);
WIRE 16 -1 (3325 4000)(3325 4075);
WIRE 16 -1 (3700 3975)(3700 4075);
WIRE 16 -1 (-3525 4675)(-3400 4675);
WIRE 16 -1 (-3525 4825)(-3525 4675);
WIRE 16 -1 (1225 4950)(1225 5000);
WIRE 16 -1 (300 2575)(975 2575);
WIRE 16 -1 (975 2575)(975 2200);
WIRE 16 -1 (675 2200)(975 2200);
WIRE 16 -1 (975 2125)(975 2200);
WIRE 16 -1 (-275 3725)(-400 3725);
WIRE 16 -1 (-400 3725)(-400 3775);
WIRE 16 -1 (-400 3775)(-275 3775);
WIRE 16 -1 (-825 3775)(-400 3775);
WIRE 16 -1 (-825 4150)(-825 3775);
WIRE 16 -1 (-1675 4150)(-825 4150);
FORCEPROP 0 LAST SIG_NAME VR_FET_SW_P5V_STBY_PVIN
J 0
(-1635 4185);
DISPLAY 0.617021 (-1635 4185);
PAINT ORANGE (-1635 4185);
FORCEPROP 2 LASTPROP $XRERR UNIQUE?
J 0
(-1875 4185);
DISPLAY 0.638298 (-1875 4185);
PAINT MONO (-1875 4185);
DISPLAY INVISIBLE (-1875 4185);
WIRE 16 -1 (-1675 4150)(-1675 4525);
WIRE 16 -1 (-1675 4525)(-2150 4525);
WIRE 16 -1 (-2150 4525)(-2150 4300);
WIRE 16 -1 (-2150 4525)(-2550 4525);
WIRE 16 -1 (-2550 4350)(-2550 4525);
WIRE 16 -1 (-2550 4525)(-2875 4525);
WIRE 16 -1 (-2875 4375)(-2875 4525);
WIRE 16 -1 (-3100 4525)(-2875 4525);
WIRE 16 -1 (-3100 4675)(-3100 4525);
WIRE 16 -1 (-3225 4525)(-3100 4525);
WIRE 16 -1 (-3225 4375)(-3225 4525);
WIRE 16 -1 (-3200 4675)(-3100 4675);
WIRE 16 2175 (-3350 3975)(-3350 4475);
WIRE 16 2175 (-2350 3975)(-3350 3975);
WIRE 16 2175 (-3350 4475)(-2350 4475);
WIRE 16 2175 (-2350 3975)(-2350 4475);
WIRE 16 -1 (2350 4625)(2975 4625);
FORCEPROP 2 LAST SIG_NAME PWRGD_P5V_STBY
J 0
(2552 4630);
DISPLAY 0.617021 (2552 4630);
PAINT ORANGE (2552 4630);
WIRE 16 -1 (1500 4625)(2150 4625);
FORCEPROP 2 LAST SIG_NAME PWRGD_P5V_STBY_R
J 0
(1577 4630);
DISPLAY 0.617021 (1577 4630);
PAINT ORANGE (1577 4630);
FORCEPROP 2 LASTPROP $XRERR UNIQUE?
J 0
(1337 4630);
DISPLAY 0.638298 (1337 4630);
PAINT MONO (1337 4630);
DISPLAY INVISIBLE (1337 4630);
WIRE 16 -1 (1500 4625)(1225 4625);
WIRE 16 -1 (1500 4500)(1500 4625);
WIRE 16 -1 (1225 4750)(1225 4625);
WIRE 16 -1 (1225 4625)(1225 3775);
WIRE 16 -1 (525 3775)(1225 3775);
WIRE 16 2175 (2375 2000)(2375 2825);
WIRE 16 2175 (3950 2000)(2375 2000);
WIRE 16 2175 (2375 2825)(3950 2825);
WIRE 16 2175 (3950 2000)(3950 2825);
WIRE 16 2175 (2450 2725)(3775 2725);
WIRE 16 2175 (1550 3900)(2325 3900);
WIRE 16 2175 (1550 2400)(1550 3900);
WIRE 16 2175 (2325 3900)(2325 2975);
WIRE 16 2175 (2325 2975)(2075 2975);
WIRE 16 2175 (2075 2400)(1550 2400);
WIRE 16 2175 (2075 2975)(2075 2400);
WIRE 16 -1 (2050 4075)(1300 4075);
FORCEPROP 2 LAST SIG_NAME VR_P5V_STBY_PHASE
J 0
(1365 4085);
DISPLAY 0.617021 (1365 4085);
PAINT ORANGE (1365 4085);
FORCEPROP 2 LASTPROP $XRERR UNIQUE?
J 0
(1125 4085);
DISPLAY 0.638298 (1125 4085);
PAINT MONO (1125 4085);
DISPLAY INVISIBLE (1125 4085);
WIRE 16 -1 (1300 4075)(1300 3675);
WIRE 16 -1 (1300 3675)(1125 3675);
WIRE 16 -1 (1300 3575)(1300 3675);
WIRE 16 -1 (1300 3525)(1300 3575);
WIRE 16 -1 (1300 3575)(525 3575);
WIRE 16 -1 (525 3525)(1300 3525);
WIRE 16 -1 (1975 3650)(1750 3650);
FORCEPROP 0 LAST SIG_NAME VR_P5V_STBY_VSENSE_R
J 0
(1415 3660);
DISPLAY 0.617021 (1415 3660);
PAINT ORANGE (1415 3660);
FORCEPROP 2 LASTPROP $XRERR UNIQUE?
J 0
(1175 3660);
DISPLAY 0.638298 (1175 3660);
PAINT MONO (1175 3660);
DISPLAY INVISIBLE (1175 3660);
WIRE 16 -1 (1750 3650)(1750 3525);
WIRE 16 -1 (1750 3325)(1750 3150);
WIRE 16 -1 (1750 3150)(1400 3150);
WIRE 16 -1 (1750 3150)(1750 3000);
WIRE 16 -1 (1400 3150)(1400 3425);
WIRE 16 -1 (1400 3425)(525 3425);
FORCEPROP 2 LAST SIG_NAME VR_P5V_STBY_VSENSE
J 0
(665 3435);
DISPLAY 0.617021 (665 3435);
PAINT ORANGE (665 3435);
FORCEPROP 2 LASTPROP $XRERR UNIQUE?
J 0
(425 3435);
DISPLAY 0.638298 (425 3435);
PAINT MONO (425 3435);
DISPLAY INVISIBLE (425 3435);
WIRE 16 2175 (1175 3975)(1175 3600);
WIRE 16 2175 (725 3975)(1175 3975);
WIRE 16 2175 (1175 3600)(725 3600);
WIRE 16 2175 (725 3600)(725 3975);
WIRE 16 -1 (925 3675)(525 3675);
FORCEPROP 2 LAST SIG_NAME VR_P5V_STBY_BOOT
J 0
(540 3685);
DISPLAY 0.617021 (540 3685);
PAINT ORANGE (540 3685);
FORCEPROP 2 LASTPROP $XRERR UNIQUE?
J 0
(300 3685);
DISPLAY 0.638298 (300 3685);
PAINT MONO (300 3685);
DISPLAY INVISIBLE (300 3685);
WIRE 16 -1 (-375 2200)(-375 2575);
FORCEPROP 2 LAST SIG_NAME VR_P5V_STBY_COMP
R 1
J 0
(-385 2660);
DISPLAY 0.617021 (-385 2660);
PAINT ORANGE (-385 2660);
FORCEPROP 2 LASTPROP $XRERR UNIQUE?
J 0
(-625 2660);
DISPLAY 0.638298 (-625 2660);
PAINT MONO (-625 2660);
DISPLAY INVISIBLE (-625 2660);
WIRE 16 -1 (-375 2200)(-300 2200);
WIRE 16 -1 (100 2575)(-375 2575);
WIRE 16 -1 (-375 2575)(-375 3275);
WIRE 16 -1 (-375 3275)(-275 3275);
WIRE 16 -1 (-100 2200)(475 2200);
FORCEPROP 0 LAST SIG_NAME VR_P5V_STBY_RC_COMP
J 0
(-10 2210);
DISPLAY 0.617021 (-10 2210);
PAINT ORANGE (-10 2210);
FORCEPROP 2 LASTPROP $XRERR UNIQUE?
J 0
(-250 2210);
DISPLAY 0.638298 (-250 2210);
PAINT MONO (-250 2210);
DISPLAY INVISIBLE (-250 2210);
WIRE 16 -1 (-1275 3575)(-275 3575);
WIRE 16 -1 (-1275 4025)(-1275 3575);
WIRE 16 -1 (-1275 4025)(-2150 4025);
FORCEPROP 2 LAST SIG_NAME VR_P5V_STBY_VIN
J 0
(-2060 4035);
DISPLAY 0.617021 (-2060 4035);
PAINT ORANGE (-2060 4035);
FORCEPROP 2 LASTPROP $XRERR UNIQUE?
J 0
(-2300 4035);
DISPLAY 0.638298 (-2300 4035);
PAINT MONO (-2300 4035);
DISPLAY INVISIBLE (-2300 4035);
WIRE 16 -1 (-2150 4100)(-2150 4025);
WIRE 16 -1 (-2150 4025)(-2150 3950);
WIRE 16 -1 (-825 2700)(-825 3325);
FORCEPROP 2 LAST SIG_NAME VR_P5V_STBY_RT
R 1
J 0
(-830 2785);
DISPLAY 0.617021 (-830 2785);
PAINT ORANGE (-830 2785);
FORCEPROP 2 LASTPROP $XRERR UNIQUE?
J 0
(-1070 2785);
DISPLAY 0.638298 (-1070 2785);
PAINT MONO (-1070 2785);
DISPLAY INVISIBLE (-1070 2785);
WIRE 16 -1 (-825 3325)(-275 3325);
WIRE 16 -1 (-1525 3475)(-275 3475);
FORCEPROP 2 LAST SIG_NAME VR_P5V_STBY_EN
J 0
(-1055 3485);
DISPLAY 0.617021 (-1055 3485);
PAINT ORANGE (-1055 3485);
FORCEPROP 2 LASTPROP $XRERR UNIQUE?
J 0
(-1295 3485);
DISPLAY 0.638298 (-1295 3485);
PAINT MONO (-1295 3485);
DISPLAY INVISIBLE (-1295 3485);
WIRE 16 -1 (-1025 3375)(-275 3375);
FORCEPROP 2 LAST SIG_NAME VR_P5V_STBY_SS
J 0
(-930 3385);
DISPLAY 0.617021 (-930 3385);
PAINT ORANGE (-930 3385);
FORCEPROP 2 LASTPROP $XRERR UNIQUE?
J 0
(-1170 3385);
DISPLAY 0.638298 (-1170 3385);
PAINT MONO (-1170 3385);
DISPLAY INVISIBLE (-1170 3385);
WIRE 16 -1 (-1025 3100)(-1025 3375);
WIRE 16 -1 (-3250 3475)(-2000 3475);
FORCEPROP 2 LAST SIG_NAME PWRGD_P12V_HSC_DLY
J 0
(-3235 3485);
DISPLAY 0.617021 (-3235 3485);
PAINT ORANGE (-3235 3485);
WIRE 16 -1 (-1725 3475)(-2000 3475);
WIRE 16 -1 (-2000 3175)(-2000 3475);
DOT 1 (-2150 4025);
DOT 1 (-2000 3475);
DOT 1 (-925 2350);
DOT 1 (-375 2575);
DOT 1 (-400 3775);
DOT 1 (-3100 4525);
DOT 1 (-2875 4525);
DOT 1 (-2550 4525);
DOT 1 (-2150 4525);
DOT 1 (975 2200);
DOT 1 (675 3225);
DOT 1 (675 3275);
DOT 1 (1300 3575);
DOT 1 (1300 3675);
DOT 1 (1750 3150);
DOT 1 (2375 4075);
DOT 1 (2550 4075);
DOT 1 (2950 3650);
DOT 1 (2950 4075);
DOT 1 (3325 3650);
DOT 1 (3175 4075);
DOT 1 (3325 4075);
DOT 1 (3600 3650);
DOT 1 (1225 4625);
DOT 1 (1500 4625);
FORCENOTE
ROOM=P5V_STBY_VR
(-3535 470) 0;
DISPLAY LEFT (-3535 470);
DISPLAY 2.446809 (-3535 470);
PAINT PURPLE (-3535 470);
FORCENOTE
BOM_COST=P5V_STBY_VR
(-3535 345) 0;
DISPLAY LEFT (-3535 345);
DISPLAY 2.446809 (-3535 345);
PAINT PURPLE (-3535 345);
FORCENOTE
5.8MS
(-1275 2775) 0;
DISPLAY LEFT (-1275 2775);
DISPLAY 0.872340 (-1275 2775);
PAINT PURPLE (-1275 2775);
FORCENOTE
650KHZ
(-800 2825) 0;
DISPLAY LEFT (-800 2825);
DISPLAY 0.872340 (-800 2825);
PAINT PURPLE (-800 2825);
FORCENOTE
COMPENSATION TYPE II
(-150 2350) 0;
DISPLAY LEFT (-150 2350);
DISPLAY 1.361702 (-150 2350);
PAINT PURPLE (-150 2350);
FORCENOTE
POINT ONLY
(1400 1700) 0;
DISPLAY LEFT (1400 1700);
DISPLAY 1.361702 (1400 1700);
PAINT PURPLE (1400 1700);
FORCENOTE
SPOF
(825 3825) 0;
DISPLAY LEFT (825 3825);
DISPLAY 1.425532 (825 3825);
PAINT PURPLE (825 3825);
FORCENOTE
CONNECT AT SINGLE
(1225 1825) 0;
DISPLAY LEFT (1225 1825);
DISPLAY 1.361702 (1225 1825);
PAINT PURPLE (1225 1825);
FORCENOTE
SPOF
(1888 3122) 0;
DISPLAY LEFT (1888 3122);
DISPLAY 1.595745 (1888 3122);
PAINT PURPLE (1888 3122);
QUIT
